FILE_TYPE = MACRO_DRAWING;
SET COLOR_WIRE YELLOW;
SET COLOR_PROP MONO;
SET COLOR_DOT WHITE;
SET COLOR_ARC YELLOW;
SET COLOR_BODY GREEN;
SET COLOR_NOTE MONO;
SET PROP_DISPLAY VALUE;
SET PAGE_NUMBER P38;
FORCEADD PVDDQ_ABC..1
(-3075 4400);
FORCEPROP 3 LASTPIN (-3075 4350) SIG_NAME PVDDQ_ABC\g
J 0
(-3065 4360);
DISPLAY 0.659574 (-3065 4360);
PAINT MONO (-3065 4360);
DISPLAY INVISIBLE (-3065 4360);
FORCEPROP 1 LAST VOLTAGE 1.2V
J 0
(-3120 4357);
DISPLAY 0.340426 (-3120 4357);
PAINT SKYBLUE (-3120 4357);
DISPLAY INVISIBLE (-3120 4357);
FORCEPROP 2 LAST CDS_LIB mstr_symbols
J 0
(-3075 4400);
PAINT ORANGE (-3075 4400);
DISPLAY INVISIBLE (-3075 4400);
FORCEPROP 1 LAST BODY_TYPE PLUMBING
J 0
(-3120 4357);
DISPLAY 0.340426 (-3120 4357);
PAINT GREEN (-3120 4357);
DISPLAY INVISIBLE (-3120 4357);
FORCEPROP 1 LAST PATH I11
J 0
(-3025 4425);
DISPLAY 0.872340 (-3025 4425);
PAINT AQUA (-3025 4425);
DISPLAY INVISIBLE (-3025 4425);
FORCEPROP 1 LAST HDL_POWER PVDDQ_ABC
J 1
(-3075 4450);
DISPLAY 0.872340 (-3075 4450);
PAINT GREEN (-3075 4450);
DISPLAY INVISIBLE (-3075 4450);
FORCEADD PVDDQ_DEF..1
(-800 4400);
FORCEPROP 3 LASTPIN (-800 4350) SIG_NAME PVDDQ_DEF\g
J 0
(-790 4360);
DISPLAY 0.659574 (-790 4360);
PAINT MONO (-790 4360);
DISPLAY INVISIBLE (-790 4360);
FORCEPROP 1 LAST VOLTAGE 1.2V
J 0
(-845 4357);
DISPLAY 0.340426 (-845 4357);
PAINT SKYBLUE (-845 4357);
DISPLAY INVISIBLE (-845 4357);
FORCEPROP 2 LAST CDS_LIB mstr_symbols
J 0
(-800 4400);
PAINT ORANGE (-800 4400);
DISPLAY INVISIBLE (-800 4400);
FORCEPROP 1 LAST BODY_TYPE PLUMBING
J 0
(-845 4357);
DISPLAY 0.340426 (-845 4357);
PAINT GREEN (-845 4357);
DISPLAY INVISIBLE (-845 4357);
FORCEPROP 1 LAST PATH I12
J 0
(-750 4425);
DISPLAY 0.872340 (-750 4425);
PAINT AQUA (-750 4425);
DISPLAY INVISIBLE (-750 4425);
FORCEPROP 1 LAST HDL_POWER PVDDQ_DEF
J 1
(-800 4450);
DISPLAY 0.872340 (-800 4450);
PAINT GREEN (-800 4450);
DISPLAY INVISIBLE (-800 4450);
FORCEADD PVCCIO_CPU0..1
(-250 4875);
FORCEPROP 3 LASTPIN (-250 4825) SIG_NAME PVCCIO_CPU0\g
J 0
(-240 4835);
DISPLAY 0.659574 (-240 4835);
PAINT MONO (-240 4835);
DISPLAY INVISIBLE (-240 4835);
FORCEPROP 1 LAST VOLTAGE 1.1V
J 0
(-295 4832);
DISPLAY 0.340426 (-295 4832);
PAINT SKYBLUE (-295 4832);
DISPLAY INVISIBLE (-295 4832);
FORCEPROP 2 LAST CDS_LIB mstr_symbols
J 0
(-250 4875);
PAINT ORANGE (-250 4875);
DISPLAY INVISIBLE (-250 4875);
FORCEPROP 1 LAST BODY_TYPE PLUMBING
J 0
(-295 4832);
DISPLAY 0.340426 (-295 4832);
PAINT GREEN (-295 4832);
DISPLAY INVISIBLE (-295 4832);
FORCEPROP 1 LAST PATH I14
J 0
(-200 4900);
DISPLAY 0.872340 (-200 4900);
PAINT AQUA (-200 4900);
DISPLAY INVISIBLE (-200 4900);
FORCEPROP 1 LAST HDL_POWER PVCCIO_CPU0
J 1
(-250 4925);
DISPLAY 0.872340 (-250 4925);
PAINT GREEN (-250 4925);
DISPLAY INVISIBLE (-250 4925);
FORCEADD GND..1
(3400 850);
FORCEPROP 3 LASTPIN (3400 900) SIG_NAME GND\g
J 0
(3410 910);
DISPLAY 0.659574 (3410 910);
PAINT MONO (3410 910);
DISPLAY INVISIBLE (3410 910);
FORCEPROP 1 LAST VOLTAGE 0.0V
J 0
(3355 807);
DISPLAY 0.340426 (3355 807);
PAINT SKYBLUE (3355 807);
DISPLAY INVISIBLE (3355 807);
FORCEPROP 2 LAST CDS_LIB mstr_symbols
J 0
(3400 850);
PAINT ORANGE (3400 850);
DISPLAY INVISIBLE (3400 850);
FORCEPROP 1 LAST SIZE 1B
J 0
(3475 800);
DISPLAY 1.170213 (3475 800);
PAINT AQUA (3475 800);
DISPLAY INVISIBLE (3475 800);
FORCEPROP 1 LAST BODY_TYPE PLUMBING
J 0
(3355 807);
DISPLAY 0.340426 (3355 807);
PAINT GREEN (3355 807);
DISPLAY INVISIBLE (3355 807);
FORCEPROP 1 LAST PATH I16
J 0
(3475 850);
DISPLAY 0.872340 (3475 850);
PAINT AQUA (3475 850);
DISPLAY INVISIBLE (3475 850);
FORCEPROP 1 LAST HDL_POWER GND
J 0
(3400 1000);
DISPLAY 1.170213 (3400 1000);
PAINT GREEN (3400 1000);
DISPLAY INVISIBLE (3400 1000);
FORCEADD PVCCIO_CPU0..1
(2900 1225);
FORCEPROP 3 LASTPIN (2900 1175) SIG_NAME PVCCIO_CPU0\g
J 0
(2910 1185);
DISPLAY 0.659574 (2910 1185);
PAINT MONO (2910 1185);
DISPLAY INVISIBLE (2910 1185);
FORCEPROP 1 LAST VOLTAGE 1.1V
J 0
(2855 1182);
DISPLAY 0.340426 (2855 1182);
PAINT SKYBLUE (2855 1182);
DISPLAY INVISIBLE (2855 1182);
FORCEPROP 2 LAST CDS_LIB mstr_symbols
J 0
(2900 1225);
PAINT ORANGE (2900 1225);
DISPLAY INVISIBLE (2900 1225);
FORCEPROP 1 LAST BODY_TYPE PLUMBING
J 0
(2855 1182);
DISPLAY 0.340426 (2855 1182);
PAINT GREEN (2855 1182);
DISPLAY INVISIBLE (2855 1182);
FORCEPROP 1 LAST PATH I17
J 0
(2950 1250);
DISPLAY 0.872340 (2950 1250);
PAINT AQUA (2950 1250);
DISPLAY INVISIBLE (2950 1250);
FORCEPROP 1 LAST HDL_POWER PVCCIO_CPU0
J 1
(2900 1275);
DISPLAY 0.872340 (2900 1275);
PAINT GREEN (2900 1275);
DISPLAY INVISIBLE (2900 1275);
FORCEADD CAP..1
(3400 1125);
FORCEPROP 1 LAST LOCATION C6D1
J 0
(3450 1225);
DISPLAY 0.617021 (3450 1225);
PAINT AQUA (3450 1225);
FORCEPROP 1 LAST PART_NUMBER E15431-001
J 0
(3450 975);
DISPLAY 0.617021 (3450 975);
PAINT BLUE (3450 975);
FORCEPROP 1 LAST VALUE 10UF
J 0
(3450 1175);
DISPLAY 0.617021 (3450 1175);
PAINT SKYBLUE (3450 1175);
FORCEPROP 1 LAST TOLERANCE 20%
J 0
(3450 1075);
DISPLAY 0.617021 (3450 1075);
PAINT SKYBLUE (3450 1075);
FORCEPROP 1 LAST PACK_TYPE 0603LF
J 0
(3450 925);
DISPLAY 0.617021 (3450 925);
PAINT SKYBLUE (3450 925);
FORCEPROP 1 LAST VOLTAGE 4V
J 0
(3450 1125);
DISPLAY 0.617021 (3450 1125);
PAINT SKYBLUE (3450 1125);
FORCEPROP 1 LAST MATERIAL X6S
J 0
(3450 1025);
DISPLAY 0.617021 (3450 1025);
PAINT SKYBLUE (3450 1025);
FORCEPROP 1 LASTPIN (3400 1025) $PN 2
J 0
(3410 1005);
DISPLAY 0.617021 (3410 1005);
PAINT ORANGE (3410 1005);
FORCEPROP 1 LASTPIN (3400 1225) $PN 1
J 0
(3410 1205);
DISPLAY 0.617021 (3410 1205);
PAINT ORANGE (3410 1205);
FORCEPROP 2 LAST CDS_LIB mstr_discrete
J 0
(3400 1125);
PAINT ORANGE (3400 1125);
DISPLAY INVISIBLE (3400 1125);
FORCEPROP 2 LAST SEC_TYPE 0603LF
J 0
(3450 1325);
DISPLAY 1.021277 (3450 1325);
PAINT ORANGE (3450 1325);
DISPLAY INVISIBLE (3450 1325);
FORCEPROP 2 LAST BOM_COST PROC_SOCKET
J 0
(3450 1325);
DISPLAY 1.021277 (3450 1325);
PAINT ORANGE (3450 1325);
DISPLAY INVISIBLE (3450 1325);
FORCEPROP 0 LAST SEC 1
J 0
(3450 1275);
PAINT ORANGE (3450 1275);
DISPLAY INVISIBLE (3450 1275);
FORCEPROP 2 LAST CDS_LOCATION C6D1
J 0
(3450 1225);
DISPLAY 0.617021 (3450 1225);
PAINT AQUA (3450 1225);
DISPLAY INVISIBLE (3450 1225);
FORCEPROP 1 LAST PATH I19
J 0
(3450 1275);
DISPLAY 0.978723 (3450 1275);
PAINT WHITE (3450 1275);
DISPLAY INVISIBLE (3450 1275);
FORCEPROP 2 LAST ROOM CPU0
J 0
(3450 1275);
DISPLAY 1.021277 (3450 1275);
PAINT ORANGE (3450 1275);
DISPLAY INVISIBLE (3450 1275);
FORCEADD PVSA_CPU0..1
(2150 4950);
FORCEPROP 3 LASTPIN (2150 4900) SIG_NAME PVSA_CPU0\g
J 0
(2160 4910);
DISPLAY 0.659574 (2160 4910);
PAINT MONO (2160 4910);
DISPLAY INVISIBLE (2160 4910);
FORCEPROP 1 LAST VOLTAGE 1.1V
J 0
(2105 4907);
DISPLAY 0.340426 (2105 4907);
PAINT SKYBLUE (2105 4907);
DISPLAY INVISIBLE (2105 4907);
FORCEPROP 2 LAST CDS_LIB mstr_symbols
J 0
(2150 4950);
PAINT ORANGE (2150 4950);
DISPLAY INVISIBLE (2150 4950);
FORCEPROP 1 LAST BODY_TYPE PLUMBING
J 0
(2105 4907);
DISPLAY 0.340426 (2105 4907);
PAINT GREEN (2105 4907);
DISPLAY INVISIBLE (2105 4907);
FORCEPROP 1 LAST PATH I24
J 0
(2200 4975);
DISPLAY 0.872340 (2200 4975);
PAINT AQUA (2200 4975);
DISPLAY INVISIBLE (2200 4975);
FORCEPROP 1 LAST HDL_POWER PVSA_CPU0
J 1
(2150 5000);
DISPLAY 0.872340 (2150 5000);
PAINT GREEN (2150 5000);
DISPLAY INVISIBLE (2150 5000);
FORCEADD VCC_CORE..1
(2500 2725);
FORCEPROP 3 LASTPIN (2500 2675) SIG_NAME PVCCIOMCP_CPU0\g
J 0
(2510 2685);
DISPLAY 0.659574 (2510 2685);
PAINT MONO (2510 2685);
DISPLAY INVISIBLE (2510 2685);
FORCEPROP 1 LAST HDL_POWER PVCCIOMCP_CPU0
J 1
(2500 2775);
DISPLAY 0.617021 (2500 2775);
PAINT GREEN (2500 2775);
FORCEPROP 2 LAST CDS_LIB mstr_symbols
J 0
(2500 2725);
PAINT ORANGE (2500 2725);
DISPLAY INVISIBLE (2500 2725);
FORCEPROP 1 LAST PATH I25
J 0
(2550 2750);
DISPLAY 0.872340 (2550 2750);
PAINT AQUA (2550 2750);
DISPLAY INVISIBLE (2550 2750);
FORCEADD VCC_CORE..1
(2500 3450);
FORCEPROP 3 LASTPIN (2500 3400) SIG_NAME PVCCMCP_CPU0\g
J 0
(2510 3410);
DISPLAY 0.659574 (2510 3410);
PAINT MONO (2510 3410);
DISPLAY INVISIBLE (2510 3410);
FORCEPROP 1 LAST HDL_POWER PVCCMCP_CPU0
J 1
(2500 3500);
DISPLAY 0.617021 (2500 3500);
PAINT GREEN (2500 3500);
FORCEPROP 2 LAST CDS_LIB mstr_symbols
J 0
(2500 3450);
PAINT ORANGE (2500 3450);
DISPLAY INVISIBLE (2500 3450);
FORCEPROP 1 LAST PATH I26
J 0
(2550 3475);
DISPLAY 0.872340 (2550 3475);
PAINT AQUA (2550 3475);
DISPLAY INVISIBLE (2550 3475);
FORCEADD PVPP_ABC..1
(2325 2025);
FORCEPROP 3 LASTPIN (2325 1975) SIG_NAME PVPP_ABC\g
J 0
(2335 1985);
DISPLAY 0.659574 (2335 1985);
PAINT MONO (2335 1985);
DISPLAY INVISIBLE (2335 1985);
FORCEPROP 1 LAST VOLTAGE 2.5V
J 0
(2280 1982);
DISPLAY 0.340426 (2280 1982);
PAINT SKYBLUE (2280 1982);
DISPLAY INVISIBLE (2280 1982);
FORCEPROP 2 LAST CDS_LIB mstr_symbols
J 0
(2325 2025);
PAINT ORANGE (2325 2025);
DISPLAY INVISIBLE (2325 2025);
FORCEPROP 2 LAST BOM_COST PVPP_KLM_VR
J 0
(2400 2125);
PAINT MONO (2400 2125);
DISPLAY INVISIBLE (2400 2125);
FORCEPROP 1 LAST BODY_TYPE PLUMBING
J 0
(2280 1982);
DISPLAY 0.340426 (2280 1982);
PAINT GREEN (2280 1982);
DISPLAY INVISIBLE (2280 1982);
FORCEPROP 1 LAST PATH I31
J 0
(2375 2050);
DISPLAY 0.872340 (2375 2050);
PAINT AQUA (2375 2050);
DISPLAY INVISIBLE (2375 2050);
FORCEPROP 2 LAST ROOM PVPP_KLM_VR
J 0
(2575 2125);
PAINT ORANGE (2575 2125);
DISPLAY INVISIBLE (2575 2125);
FORCEPROP 1 LAST HDL_POWER PVPP_ABC
J 1
(2325 2075);
DISPLAY 0.872340 (2325 2075);
PAINT GREEN (2325 2075);
DISPLAY INVISIBLE (2325 2075);
FORCEADD SKX_EXT_B..20
(-1950 2650);
FORCEPROP 1 LAST LOCATION U5D1
J 0
(-2750 4200);
DISPLAY 0.617021 (-2750 4200);
PAINT AQUA (-2750 4200);
FORCEPROP 1 LAST PART_NUMBER TBD
J 0
(-2750 1150);
DISPLAY 0.617021 (-2750 1150);
PAINT BLUE (-2750 1150);
FORCEPROP 1 LAST MATERIAL IC
J 0
(-2750 4150);
DISPLAY 0.617021 (-2750 4150);
PAINT SKYBLUE (-2750 4150);
FORCEPROP 2 LASTPIN (-1100 3950) $PN EE44
J 0
(-1090 3960);
DISPLAY 0.617021 (-1090 3960);
PAINT ORANGE (-1090 3960);
FORCEPROP 2 LASTPIN (-1100 3900) $PN EF45
J 0
(-1090 3910);
DISPLAY 0.617021 (-1090 3910);
PAINT ORANGE (-1090 3910);
FORCEPROP 2 LASTPIN (-1100 3850) $PN DB53
J 0
(-1090 3860);
DISPLAY 0.617021 (-1090 3860);
PAINT ORANGE (-1090 3860);
FORCEPROP 2 LASTPIN (-1100 3800) $PN DB55
J 0
(-1090 3810);
DISPLAY 0.617021 (-1090 3810);
PAINT ORANGE (-1090 3810);
FORCEPROP 2 LASTPIN (-1100 3750) $PN DB57
J 0
(-1090 3760);
DISPLAY 0.617021 (-1090 3760);
PAINT ORANGE (-1090 3760);
FORCEPROP 2 LASTPIN (-1100 3700) $PN DB59
J 0
(-1090 3710);
DISPLAY 0.617021 (-1090 3710);
PAINT ORANGE (-1090 3710);
FORCEPROP 2 LASTPIN (-1100 3650) $PN DB61
J 0
(-1090 3660);
DISPLAY 0.617021 (-1090 3660);
PAINT ORANGE (-1090 3660);
FORCEPROP 2 LASTPIN (-1100 3600) $PN DB63
J 0
(-1090 3610);
DISPLAY 0.617021 (-1090 3610);
PAINT ORANGE (-1090 3610);
FORCEPROP 2 LASTPIN (-1100 3550) $PN DD45
J 0
(-1090 3560);
DISPLAY 0.617021 (-1090 3560);
PAINT ORANGE (-1090 3560);
FORCEPROP 2 LASTPIN (-1100 3500) $PN DH45
J 0
(-1090 3510);
DISPLAY 0.617021 (-1090 3510);
PAINT ORANGE (-1090 3510);
FORCEPROP 2 LASTPIN (-1100 3450) $PN DH47
J 0
(-1090 3460);
DISPLAY 0.617021 (-1090 3460);
PAINT ORANGE (-1090 3460);
FORCEPROP 2 LASTPIN (-1100 3400) $PN DH49
J 0
(-1090 3410);
DISPLAY 0.617021 (-1090 3410);
PAINT ORANGE (-1090 3410);
FORCEPROP 2 LASTPIN (-1100 3350) $PN DH51
J 0
(-1090 3360);
DISPLAY 0.617021 (-1090 3360);
PAINT ORANGE (-1090 3360);
FORCEPROP 2 LASTPIN (-1100 3300) $PN DH53
J 0
(-1090 3310);
DISPLAY 0.617021 (-1090 3310);
PAINT ORANGE (-1090 3310);
FORCEPROP 2 LASTPIN (-1100 3250) $PN DH55
J 0
(-1090 3260);
DISPLAY 0.617021 (-1090 3260);
PAINT ORANGE (-1090 3260);
FORCEPROP 2 LASTPIN (-1100 3200) $PN DH57
J 0
(-1090 3210);
DISPLAY 0.617021 (-1090 3210);
PAINT ORANGE (-1090 3210);
FORCEPROP 2 LASTPIN (-1100 3150) $PN DH59
J 0
(-1090 3160);
DISPLAY 0.617021 (-1090 3160);
PAINT ORANGE (-1090 3160);
FORCEPROP 2 LASTPIN (-1100 3100) $PN DH61
J 0
(-1090 3110);
DISPLAY 0.617021 (-1090 3110);
PAINT ORANGE (-1090 3110);
FORCEPROP 2 LASTPIN (-1100 3050) $PN DH63
J 0
(-1090 3060);
DISPLAY 0.617021 (-1090 3060);
PAINT ORANGE (-1090 3060);
FORCEPROP 2 LASTPIN (-1100 3000) $PN DJ64
J 0
(-1090 3010);
DISPLAY 0.617021 (-1090 3010);
PAINT ORANGE (-1090 3010);
FORCEPROP 2 LASTPIN (-1100 2950) $PN DL46
J 0
(-1090 2960);
DISPLAY 0.617021 (-1090 2960);
PAINT ORANGE (-1090 2960);
FORCEPROP 2 LASTPIN (-1100 2900) $PN DL48
J 0
(-1090 2910);
DISPLAY 0.617021 (-1090 2910);
PAINT ORANGE (-1090 2910);
FORCEPROP 2 LASTPIN (-1100 2850) $PN DL50
J 0
(-1090 2860);
DISPLAY 0.617021 (-1090 2860);
PAINT ORANGE (-1090 2860);
FORCEPROP 2 LASTPIN (-1100 2800) $PN DL52
J 0
(-1090 2810);
DISPLAY 0.617021 (-1090 2810);
PAINT ORANGE (-1090 2810);
FORCEPROP 2 LASTPIN (-1100 2750) $PN DL54
J 0
(-1090 2760);
DISPLAY 0.617021 (-1090 2760);
PAINT ORANGE (-1090 2760);
FORCEPROP 2 LASTPIN (-1100 2700) $PN DL56
J 0
(-1090 2710);
DISPLAY 0.617021 (-1090 2710);
PAINT ORANGE (-1090 2710);
FORCEPROP 2 LASTPIN (-1100 2650) $PN DL58
J 0
(-1090 2660);
DISPLAY 0.617021 (-1090 2660);
PAINT ORANGE (-1090 2660);
FORCEPROP 2 LASTPIN (-1100 2600) $PN DL60
J 0
(-1090 2610);
DISPLAY 0.617021 (-1090 2610);
PAINT ORANGE (-1090 2610);
FORCEPROP 2 LASTPIN (-1100 2550) $PN DL62
J 0
(-1090 2560);
DISPLAY 0.617021 (-1090 2560);
PAINT ORANGE (-1090 2560);
FORCEPROP 2 LASTPIN (-1100 2500) $PN DU46
J 0
(-1090 2510);
DISPLAY 0.617021 (-1090 2510);
PAINT ORANGE (-1090 2510);
FORCEPROP 2 LASTPIN (-1100 2450) $PN DU48
J 0
(-1090 2460);
DISPLAY 0.617021 (-1090 2460);
PAINT ORANGE (-1090 2460);
FORCEPROP 2 LASTPIN (-1100 2400) $PN DU50
J 0
(-1090 2410);
DISPLAY 0.617021 (-1090 2410);
PAINT ORANGE (-1090 2410);
FORCEPROP 2 LASTPIN (-1100 2350) $PN DU52
J 0
(-1090 2360);
DISPLAY 0.617021 (-1090 2360);
PAINT ORANGE (-1090 2360);
FORCEPROP 2 LASTPIN (-1100 2300) $PN DU54
J 0
(-1090 2310);
DISPLAY 0.617021 (-1090 2310);
PAINT ORANGE (-1090 2310);
FORCEPROP 2 LASTPIN (-1100 2250) $PN DU56
J 0
(-1090 2260);
DISPLAY 0.617021 (-1090 2260);
PAINT ORANGE (-1090 2260);
FORCEPROP 2 LASTPIN (-1100 2200) $PN DU58
J 0
(-1090 2210);
DISPLAY 0.617021 (-1090 2210);
PAINT ORANGE (-1090 2210);
FORCEPROP 2 LASTPIN (-1100 2150) $PN DU60
J 0
(-1090 2160);
DISPLAY 0.617021 (-1090 2160);
PAINT ORANGE (-1090 2160);
FORCEPROP 2 LASTPIN (-1100 2100) $PN DU62
J 0
(-1090 2110);
DISPLAY 0.617021 (-1090 2110);
PAINT ORANGE (-1090 2110);
FORCEPROP 2 LASTPIN (-1100 2050) $PN DU64
J 0
(-1090 2060);
DISPLAY 0.617021 (-1090 2060);
PAINT ORANGE (-1090 2060);
FORCEPROP 2 LASTPIN (-1100 2000) $PN EC46
J 0
(-1090 2010);
DISPLAY 0.617021 (-1090 2010);
PAINT ORANGE (-1090 2010);
FORCEPROP 2 LASTPIN (-1100 1950) $PN EC48
J 0
(-1090 1960);
DISPLAY 0.617021 (-1090 1960);
PAINT ORANGE (-1090 1960);
FORCEPROP 2 LASTPIN (-1100 1900) $PN EC50
J 0
(-1090 1910);
DISPLAY 0.617021 (-1090 1910);
PAINT ORANGE (-1090 1910);
FORCEPROP 2 LASTPIN (-1100 1850) $PN EC52
J 0
(-1090 1860);
DISPLAY 0.617021 (-1090 1860);
PAINT ORANGE (-1090 1860);
FORCEPROP 2 LASTPIN (-1100 1800) $PN EC54
J 0
(-1090 1810);
DISPLAY 0.617021 (-1090 1810);
PAINT ORANGE (-1090 1810);
FORCEPROP 2 LASTPIN (-1100 1750) $PN EC56
J 0
(-1090 1760);
DISPLAY 0.617021 (-1090 1760);
PAINT ORANGE (-1090 1760);
FORCEPROP 2 LASTPIN (-1100 1700) $PN EC58
J 0
(-1090 1710);
DISPLAY 0.617021 (-1090 1710);
PAINT ORANGE (-1090 1710);
FORCEPROP 2 LASTPIN (-1100 1650) $PN EC60
J 0
(-1090 1660);
DISPLAY 0.617021 (-1090 1660);
PAINT ORANGE (-1090 1660);
FORCEPROP 2 LASTPIN (-1100 1600) $PN EC62
J 0
(-1090 1610);
DISPLAY 0.617021 (-1090 1610);
PAINT ORANGE (-1090 1610);
FORCEPROP 2 LASTPIN (-1100 1550) $PN EF49
J 0
(-1090 1560);
DISPLAY 0.617021 (-1090 1560);
PAINT ORANGE (-1090 1560);
FORCEPROP 2 LASTPIN (-1100 1450) $PN EF53
J 0
(-1090 1460);
DISPLAY 0.617021 (-1090 1460);
PAINT ORANGE (-1090 1460);
FORCEPROP 2 LASTPIN (-1100 1400) $PN EF59
J 0
(-1090 1410);
DISPLAY 0.617021 (-1090 1410);
PAINT ORANGE (-1090 1410);
FORCEPROP 2 LASTPIN (-2800 3950) $PN B47
J 2
(-2810 3960);
DISPLAY 0.617021 (-2810 3960);
PAINT ORANGE (-2810 3960);
FORCEPROP 2 LASTPIN (-2800 3900) $PN C46
J 2
(-2810 3910);
DISPLAY 0.617021 (-2810 3910);
PAINT ORANGE (-2810 3910);
FORCEPROP 2 LASTPIN (-2800 3850) $PN D45
J 2
(-2810 3860);
DISPLAY 0.617021 (-2810 3860);
PAINT ORANGE (-2810 3860);
FORCEPROP 2 LASTPIN (-2800 3800) $PN AF63
J 2
(-2810 3810);
DISPLAY 0.617021 (-2810 3810);
PAINT ORANGE (-2810 3810);
FORCEPROP 2 LASTPIN (-2800 3750) $PN AF61
J 2
(-2810 3760);
DISPLAY 0.617021 (-2810 3760);
PAINT ORANGE (-2810 3760);
FORCEPROP 2 LASTPIN (-2800 3700) $PN AF59
J 2
(-2810 3710);
DISPLAY 0.617021 (-2810 3710);
PAINT ORANGE (-2810 3710);
FORCEPROP 2 LASTPIN (-2800 3650) $PN AF57
J 2
(-2810 3660);
DISPLAY 0.617021 (-2810 3660);
PAINT ORANGE (-2810 3660);
FORCEPROP 2 LASTPIN (-2800 3600) $PN AF55
J 2
(-2810 3610);
DISPLAY 0.617021 (-2810 3610);
PAINT ORANGE (-2810 3610);
FORCEPROP 2 LASTPIN (-2800 3550) $PN AD45
J 2
(-2810 3560);
DISPLAY 0.617021 (-2810 3560);
PAINT ORANGE (-2810 3560);
FORCEPROP 2 LASTPIN (-2800 3500) $PN Y63
J 2
(-2810 3510);
DISPLAY 0.617021 (-2810 3510);
PAINT ORANGE (-2810 3510);
FORCEPROP 2 LASTPIN (-2800 3450) $PN Y61
J 2
(-2810 3460);
DISPLAY 0.617021 (-2810 3460);
PAINT ORANGE (-2810 3460);
FORCEPROP 2 LASTPIN (-2800 3400) $PN Y59
J 2
(-2810 3410);
DISPLAY 0.617021 (-2810 3410);
PAINT ORANGE (-2810 3410);
FORCEPROP 2 LASTPIN (-2800 3350) $PN Y57
J 2
(-2810 3360);
DISPLAY 0.617021 (-2810 3360);
PAINT ORANGE (-2810 3360);
FORCEPROP 2 LASTPIN (-2800 3300) $PN Y55
J 2
(-2810 3310);
DISPLAY 0.617021 (-2810 3310);
PAINT ORANGE (-2810 3310);
FORCEPROP 2 LASTPIN (-2800 3250) $PN Y53
J 2
(-2810 3260);
DISPLAY 0.617021 (-2810 3260);
PAINT ORANGE (-2810 3260);
FORCEPROP 2 LASTPIN (-2800 3200) $PN Y51
J 2
(-2810 3210);
DISPLAY 0.617021 (-2810 3210);
PAINT ORANGE (-2810 3210);
FORCEPROP 2 LASTPIN (-2800 3150) $PN Y49
J 2
(-2810 3160);
DISPLAY 0.617021 (-2810 3160);
PAINT ORANGE (-2810 3160);
FORCEPROP 2 LASTPIN (-2800 3100) $PN Y47
J 2
(-2810 3110);
DISPLAY 0.617021 (-2810 3110);
PAINT ORANGE (-2810 3110);
FORCEPROP 2 LASTPIN (-2800 3050) $PN Y45
J 2
(-2810 3060);
DISPLAY 0.617021 (-2810 3060);
PAINT ORANGE (-2810 3060);
FORCEPROP 2 LASTPIN (-2800 3000) $PN W64
J 2
(-2810 3010);
DISPLAY 0.617021 (-2810 3010);
PAINT ORANGE (-2810 3010);
FORCEPROP 2 LASTPIN (-2800 2950) $PN U62
J 2
(-2810 2960);
DISPLAY 0.617021 (-2810 2960);
PAINT ORANGE (-2810 2960);
FORCEPROP 2 LASTPIN (-2800 2900) $PN U60
J 2
(-2810 2910);
DISPLAY 0.617021 (-2810 2910);
PAINT ORANGE (-2810 2910);
FORCEPROP 2 LASTPIN (-2800 2850) $PN U58
J 2
(-2810 2860);
DISPLAY 0.617021 (-2810 2860);
PAINT ORANGE (-2810 2860);
FORCEPROP 2 LASTPIN (-2800 2800) $PN U56
J 2
(-2810 2810);
DISPLAY 0.617021 (-2810 2810);
PAINT ORANGE (-2810 2810);
FORCEPROP 2 LASTPIN (-2800 2750) $PN U54
J 2
(-2810 2760);
DISPLAY 0.617021 (-2810 2760);
PAINT ORANGE (-2810 2760);
FORCEPROP 2 LASTPIN (-2800 2700) $PN U52
J 2
(-2810 2710);
DISPLAY 0.617021 (-2810 2710);
PAINT ORANGE (-2810 2710);
FORCEPROP 2 LASTPIN (-2800 2650) $PN U50
J 2
(-2810 2660);
DISPLAY 0.617021 (-2810 2660);
PAINT ORANGE (-2810 2660);
FORCEPROP 2 LASTPIN (-2800 2600) $PN U48
J 2
(-2810 2610);
DISPLAY 0.617021 (-2810 2610);
PAINT ORANGE (-2810 2610);
FORCEPROP 2 LASTPIN (-2800 2550) $PN U46
J 2
(-2810 2560);
DISPLAY 0.617021 (-2810 2560);
PAINT ORANGE (-2810 2560);
FORCEPROP 2 LASTPIN (-2800 2500) $PN N64
J 2
(-2810 2510);
DISPLAY 0.617021 (-2810 2510);
PAINT ORANGE (-2810 2510);
FORCEPROP 2 LASTPIN (-2800 2450) $PN L62
J 2
(-2810 2460);
DISPLAY 0.617021 (-2810 2460);
PAINT ORANGE (-2810 2460);
FORCEPROP 2 LASTPIN (-2800 2400) $PN L60
J 2
(-2810 2410);
DISPLAY 0.617021 (-2810 2410);
PAINT ORANGE (-2810 2410);
FORCEPROP 2 LASTPIN (-2800 2350) $PN L58
J 2
(-2810 2360);
DISPLAY 0.617021 (-2810 2360);
PAINT ORANGE (-2810 2360);
FORCEPROP 2 LASTPIN (-2800 2300) $PN L56
J 2
(-2810 2310);
DISPLAY 0.617021 (-2810 2310);
PAINT ORANGE (-2810 2310);
FORCEPROP 2 LASTPIN (-2800 2250) $PN L54
J 2
(-2810 2260);
DISPLAY 0.617021 (-2810 2260);
PAINT ORANGE (-2810 2260);
FORCEPROP 2 LASTPIN (-2800 2200) $PN L52
J 2
(-2810 2210);
DISPLAY 0.617021 (-2810 2210);
PAINT ORANGE (-2810 2210);
FORCEPROP 2 LASTPIN (-2800 2150) $PN L50
J 2
(-2810 2160);
DISPLAY 0.617021 (-2810 2160);
PAINT ORANGE (-2810 2160);
FORCEPROP 2 LASTPIN (-2800 2100) $PN L48
J 2
(-2810 2110);
DISPLAY 0.617021 (-2810 2110);
PAINT ORANGE (-2810 2110);
FORCEPROP 2 LASTPIN (-2800 2050) $PN L46
J 2
(-2810 2060);
DISPLAY 0.617021 (-2810 2060);
PAINT ORANGE (-2810 2060);
FORCEPROP 2 LASTPIN (-2800 2000) $PN E64
J 2
(-2810 2010);
DISPLAY 0.617021 (-2810 2010);
PAINT ORANGE (-2810 2010);
FORCEPROP 2 LASTPIN (-2800 1950) $PN E62
J 2
(-2810 1960);
DISPLAY 0.617021 (-2810 1960);
PAINT ORANGE (-2810 1960);
FORCEPROP 2 LASTPIN (-2800 1900) $PN E60
J 2
(-2810 1910);
DISPLAY 0.617021 (-2810 1910);
PAINT ORANGE (-2810 1910);
FORCEPROP 2 LASTPIN (-2800 1850) $PN E58
J 2
(-2810 1860);
DISPLAY 0.617021 (-2810 1860);
PAINT ORANGE (-2810 1860);
FORCEPROP 2 LASTPIN (-2800 1800) $PN E56
J 2
(-2810 1810);
DISPLAY 0.617021 (-2810 1810);
PAINT ORANGE (-2810 1810);
FORCEPROP 2 LASTPIN (-2800 1750) $PN E54
J 2
(-2810 1760);
DISPLAY 0.617021 (-2810 1760);
PAINT ORANGE (-2810 1760);
FORCEPROP 2 LASTPIN (-2800 1700) $PN E52
J 2
(-2810 1710);
DISPLAY 0.617021 (-2810 1710);
PAINT ORANGE (-2810 1710);
FORCEPROP 2 LASTPIN (-2800 1650) $PN E50
J 2
(-2810 1660);
DISPLAY 0.617021 (-2810 1660);
PAINT ORANGE (-2810 1660);
FORCEPROP 2 LASTPIN (-2800 1600) $PN E48
J 2
(-2810 1610);
DISPLAY 0.617021 (-2810 1610);
PAINT ORANGE (-2810 1610);
FORCEPROP 2 LASTPIN (-2800 1550) $PN E46
J 2
(-2810 1560);
DISPLAY 0.617021 (-2810 1560);
PAINT ORANGE (-2810 1560);
FORCEPROP 2 LASTPIN (-2800 1450) $PN B59
J 2
(-2810 1460);
DISPLAY 0.617021 (-2810 1460);
PAINT ORANGE (-2810 1460);
FORCEPROP 2 LASTPIN (-2800 1400) $PN B53
J 2
(-2810 1410);
DISPLAY 0.617021 (-2810 1410);
PAINT ORANGE (-2810 1410);
FORCEPROP 2 LASTPIN (-2800 1350) $PN B49
J 2
(-2810 1360);
DISPLAY 0.617021 (-2810 1360);
PAINT ORANGE (-2810 1360);
FORCEPROP 1 LAST PACK_TYPE BGA1
J 0
(-2750 4250);
PAINT SKYBLUE (-2750 4250);
DISPLAY INVISIBLE (-2750 4250);
FORCEPROP 2 LAST SEC_TYPE BGA1
J 0
(-2750 4250);
DISPLAY 1.021277 (-2750 4250);
PAINT ORANGE (-2750 4250);
DISPLAY INVISIBLE (-2750 4250);
FORCEPROP 2 LAST CDS_LIB chpset_lib
J 0
(-1950 2650);
PAINT ORANGE (-1950 2650);
DISPLAY INVISIBLE (-1950 2650);
FORCEPROP 2 LAST SEC 20
J 0
(-2750 4250);
DISPLAY 0.680851 (-2750 4250);
PAINT MONO (-2750 4250);
DISPLAY INVISIBLE (-2750 4250);
FORCEPROP 2 LAST CDS_LOCATION U5D1
J 0
(-2750 4200);
DISPLAY 0.617021 (-2750 4200);
PAINT AQUA (-2750 4200);
DISPLAY INVISIBLE (-2750 4200);
FORCEPROP 1 LAST PATH I33
J 0
(-1950 4150);
PAINT GREEN (-1950 4150);
DISPLAY INVISIBLE (-1950 4150);
FORCEPROP 0 LAST ROOM CPU0
J 0
(-2750 4300);
DISPLAY 1.021277 (-2750 4300);
PAINT ORANGE (-2750 4300);
DISPLAY INVISIBLE (-2750 4300);
FORCEADD SKX_EXT_B..21
(1050 2725);
FORCEPROP 1 LAST LOCATION U5D1
J 0
(200 4975);
DISPLAY 0.617021 (200 4975);
PAINT AQUA (200 4975);
FORCEPROP 1 LAST PART_NUMBER TBD
J 0
(200 475);
DISPLAY 0.617021 (200 475);
PAINT BLUE (200 475);
FORCEPROP 1 LAST MATERIAL IC
J 0
(200 4925);
DISPLAY 0.617021 (200 4925);
PAINT SKYBLUE (200 4925);
FORCEPROP 2 LASTPIN (1950 4725) $PN CB65
J 0
(1960 4735);
DISPLAY 0.617021 (1960 4735);
PAINT ORANGE (1960 4735);
FORCEPROP 2 LASTPIN (1950 4675) $PN CB67
J 0
(1960 4685);
DISPLAY 0.617021 (1960 4685);
PAINT ORANGE (1960 4685);
FORCEPROP 2 LASTPIN (1950 4625) $PN CB69
J 0
(1960 4635);
DISPLAY 0.617021 (1960 4635);
PAINT ORANGE (1960 4635);
FORCEPROP 2 LASTPIN (1950 4575) $PN CC66
J 0
(1960 4585);
DISPLAY 0.617021 (1960 4585);
PAINT ORANGE (1960 4585);
FORCEPROP 2 LASTPIN (1950 4525) $PN CC68
J 0
(1960 4535);
DISPLAY 0.617021 (1960 4535);
PAINT ORANGE (1960 4535);
FORCEPROP 2 LASTPIN (1950 4475) $PN CC70
J 0
(1960 4485);
DISPLAY 0.617021 (1960 4485);
PAINT ORANGE (1960 4485);
FORCEPROP 2 LASTPIN (1950 4425) $PN CD65
J 0
(1960 4435);
DISPLAY 0.617021 (1960 4435);
PAINT ORANGE (1960 4435);
FORCEPROP 2 LASTPIN (1950 4375) $PN CD67
J 0
(1960 4385);
DISPLAY 0.617021 (1960 4385);
PAINT ORANGE (1960 4385);
FORCEPROP 2 LASTPIN (1950 4325) $PN CD69
J 0
(1960 4335);
DISPLAY 0.617021 (1960 4335);
PAINT ORANGE (1960 4335);
FORCEPROP 2 LASTPIN (1950 4275) $PN CD71
J 0
(1960 4285);
DISPLAY 0.617021 (1960 4285);
PAINT ORANGE (1960 4285);
FORCEPROP 2 LASTPIN (1950 4225) $PN CE64
J 0
(1960 4235);
DISPLAY 0.617021 (1960 4235);
PAINT ORANGE (1960 4235);
FORCEPROP 2 LASTPIN (1950 4175) $PN CE66
J 0
(1960 4185);
DISPLAY 0.617021 (1960 4185);
PAINT ORANGE (1960 4185);
FORCEPROP 2 LASTPIN (1950 4125) $PN CE68
J 0
(1960 4135);
DISPLAY 0.617021 (1960 4135);
PAINT ORANGE (1960 4135);
FORCEPROP 2 LASTPIN (1950 4075) $PN CE72
J 0
(1960 4085);
DISPLAY 0.617021 (1960 4085);
PAINT ORANGE (1960 4085);
FORCEPROP 2 LASTPIN (1950 4025) $PN CE74
J 0
(1960 4035);
DISPLAY 0.617021 (1960 4035);
PAINT ORANGE (1960 4035);
FORCEPROP 2 LASTPIN (1950 3975) $PN CF65
J 0
(1960 3985);
DISPLAY 0.617021 (1960 3985);
PAINT ORANGE (1960 3985);
FORCEPROP 2 LASTPIN (1950 3925) $PN CF67
J 0
(1960 3935);
DISPLAY 0.617021 (1960 3935);
PAINT ORANGE (1960 3935);
FORCEPROP 2 LASTPIN (1950 3875) $PN CF73
J 0
(1960 3885);
DISPLAY 0.617021 (1960 3885);
PAINT ORANGE (1960 3885);
FORCEPROP 2 LASTPIN (1950 3825) $PN CF75
J 0
(1960 3835);
DISPLAY 0.617021 (1960 3835);
PAINT ORANGE (1960 3835);
FORCEPROP 2 LASTPIN (1950 3775) $PN CG64
J 0
(1960 3785);
DISPLAY 0.617021 (1960 3785);
PAINT ORANGE (1960 3785);
FORCEPROP 2 LASTPIN (1950 3725) $PN CG66
J 0
(1960 3735);
DISPLAY 0.617021 (1960 3735);
PAINT ORANGE (1960 3735);
FORCEPROP 2 LASTPIN (1950 3675) $PN CG74
J 0
(1960 3685);
DISPLAY 0.617021 (1960 3685);
PAINT ORANGE (1960 3685);
FORCEPROP 2 LASTPIN (1950 3625) $PN CH65
J 0
(1960 3635);
DISPLAY 0.617021 (1960 3635);
PAINT ORANGE (1960 3635);
FORCEPROP 2 LASTPIN (1950 3575) $PN CH75
J 0
(1960 3585);
DISPLAY 0.617021 (1960 3585);
PAINT ORANGE (1960 3585);
FORCEPROP 2 LASTPIN (1950 3525) $PN CJ64
J 0
(1960 3535);
DISPLAY 0.617021 (1960 3535);
PAINT ORANGE (1960 3535);
FORCEPROP 2 LASTPIN (1950 3475) $PN CJ66
J 0
(1960 3485);
DISPLAY 0.617021 (1960 3485);
PAINT ORANGE (1960 3485);
FORCEPROP 2 LASTPIN (150 4725) $PN AR28
J 2
(140 4735);
DISPLAY 0.617021 (140 4735);
PAINT ORANGE (140 4735);
FORCEPROP 2 LASTPIN (150 4675) $PN AL28
J 2
(140 4685);
DISPLAY 0.617021 (140 4685);
PAINT ORANGE (140 4685);
FORCEPROP 2 LASTPIN (150 4625) $PN AM29
J 2
(140 4635);
DISPLAY 0.617021 (140 4635);
PAINT ORANGE (140 4635);
FORCEPROP 2 LASTPIN (150 4575) $PN AG34
J 2
(140 4585);
DISPLAY 0.617021 (140 4585);
PAINT ORANGE (140 4585);
FORCEPROP 2 LASTPIN (150 4525) $PN AE34
J 2
(140 4535);
DISPLAY 0.617021 (140 4535);
PAINT ORANGE (140 4535);
FORCEPROP 2 LASTPIN (150 4475) $PN AD35
J 2
(140 4485);
DISPLAY 0.617021 (140 4485);
PAINT ORANGE (140 4485);
FORCEPROP 2 LASTPIN (150 4425) $PN AF35
J 2
(140 4435);
DISPLAY 0.617021 (140 4435);
PAINT ORANGE (140 4435);
FORCEPROP 2 LASTPIN (150 4375) $PN AC36
J 2
(140 4385);
DISPLAY 0.617021 (140 4385);
PAINT ORANGE (140 4385);
FORCEPROP 2 LASTPIN (150 4325) $PN AD37
J 2
(140 4335);
DISPLAY 0.617021 (140 4335);
PAINT ORANGE (140 4335);
FORCEPROP 2 LASTPIN (150 4275) $PN AE36
J 2
(140 4285);
DISPLAY 0.617021 (140 4285);
PAINT ORANGE (140 4285);
FORCEPROP 2 LASTPIN (150 4225) $PN BF27
J 2
(140 4235);
DISPLAY 0.617021 (140 4235);
PAINT ORANGE (140 4235);
FORCEPROP 2 LASTPIN (150 4175) $PN BG26
J 2
(140 4185);
DISPLAY 0.617021 (140 4185);
PAINT ORANGE (140 4185);
FORCEPROP 2 LASTPIN (150 4125) $PN BH25
J 2
(140 4135);
DISPLAY 0.617021 (140 4135);
PAINT ORANGE (140 4135);
FORCEPROP 2 LASTPIN (150 4075) $PN BH27
J 2
(140 4085);
DISPLAY 0.617021 (140 4085);
PAINT ORANGE (140 4085);
FORCEPROP 2 LASTPIN (150 4025) $PN BJ26
J 2
(140 4035);
DISPLAY 0.617021 (140 4035);
PAINT ORANGE (140 4035);
FORCEPROP 2 LASTPIN (150 3975) $PN BK25
J 2
(140 3985);
DISPLAY 0.617021 (140 3985);
PAINT ORANGE (140 3985);
FORCEPROP 2 LASTPIN (150 3925) $PN BK27
J 2
(140 3935);
DISPLAY 0.617021 (140 3935);
PAINT ORANGE (140 3935);
FORCEPROP 2 LASTPIN (150 3875) $PN BL26
J 2
(140 3885);
DISPLAY 0.617021 (140 3885);
PAINT ORANGE (140 3885);
FORCEPROP 2 LASTPIN (150 3825) $PN BM27
J 2
(140 3835);
DISPLAY 0.617021 (140 3835);
PAINT ORANGE (140 3835);
FORCEPROP 2 LASTPIN (150 3775) $PN CH27
J 2
(140 3785);
DISPLAY 0.617021 (140 3785);
PAINT ORANGE (140 3785);
FORCEPROP 2 LASTPIN (150 3725) $PN CJ28
J 2
(140 3735);
DISPLAY 0.617021 (140 3735);
PAINT ORANGE (140 3735);
FORCEPROP 2 LASTPIN (150 3675) $PN CC26
J 2
(140 3685);
DISPLAY 0.617021 (140 3685);
PAINT ORANGE (140 3685);
FORCEPROP 2 LASTPIN (150 3625) $PN CD27
J 2
(140 3635);
DISPLAY 0.617021 (140 3635);
PAINT ORANGE (140 3635);
FORCEPROP 2 LASTPIN (150 3575) $PN CF27
J 2
(140 3585);
DISPLAY 0.617021 (140 3585);
PAINT ORANGE (140 3585);
FORCEPROP 2 LASTPIN (150 3525) $PN AV27
J 2
(140 3535);
DISPLAY 0.617021 (140 3535);
PAINT ORANGE (140 3535);
FORCEPROP 2 LASTPIN (150 3475) $PN AW26
J 2
(140 3485);
DISPLAY 0.617021 (140 3485);
PAINT ORANGE (140 3485);
FORCEPROP 2 LASTPIN (150 3425) $PN AY27
J 2
(140 3435);
DISPLAY 0.617021 (140 3435);
PAINT ORANGE (140 3435);
FORCEPROP 2 LASTPIN (150 3375) $PN BA26
J 2
(140 3385);
DISPLAY 0.617021 (140 3385);
PAINT ORANGE (140 3385);
FORCEPROP 2 LASTPIN (150 3325) $PN BB27
J 2
(140 3335);
DISPLAY 0.617021 (140 3335);
PAINT ORANGE (140 3335);
FORCEPROP 2 LASTPIN (150 3275) $PN BC26
J 2
(140 3285);
DISPLAY 0.617021 (140 3285);
PAINT ORANGE (140 3285);
FORCEPROP 2 LASTPIN (150 3225) $PN W10
J 2
(140 3235);
DISPLAY 0.617021 (140 3235);
PAINT ORANGE (140 3235);
FORCEPROP 2 LASTPIN (150 3175) $PN N18
J 2
(140 3185);
DISPLAY 0.617021 (140 3185);
PAINT ORANGE (140 3185);
FORCEPROP 2 LASTPIN (150 3125) $PN M9
J 2
(140 3135);
DISPLAY 0.617021 (140 3135);
PAINT ORANGE (140 3135);
FORCEPROP 2 LASTPIN (150 3075) $PN M7
J 2
(140 3085);
DISPLAY 0.617021 (140 3085);
PAINT ORANGE (140 3085);
FORCEPROP 2 LASTPIN (150 3025) $PN K15
J 2
(140 3035);
DISPLAY 0.617021 (140 3035);
PAINT ORANGE (140 3035);
FORCEPROP 2 LASTPIN (150 2975) $PN J2
J 2
(140 2985);
DISPLAY 0.617021 (140 2985);
PAINT ORANGE (140 2985);
FORCEPROP 2 LASTPIN (150 2925) $PN EB15
J 2
(140 2935);
DISPLAY 0.617021 (140 2935);
PAINT ORANGE (140 2935);
FORCEPROP 2 LASTPIN (150 2875) $PN EA12
J 2
(140 2885);
DISPLAY 0.617021 (140 2885);
PAINT ORANGE (140 2885);
FORCEPROP 2 LASTPIN (150 2825) $PN DU20
J 2
(140 2835);
DISPLAY 0.617021 (140 2835);
PAINT ORANGE (140 2835);
FORCEPROP 2 LASTPIN (150 2775) $PN DR2
J 2
(140 2785);
DISPLAY 0.617021 (140 2785);
PAINT ORANGE (140 2785);
FORCEPROP 2 LASTPIN (150 2725) $PN DR10
J 2
(140 2735);
DISPLAY 0.617021 (140 2735);
PAINT ORANGE (140 2735);
FORCEPROP 2 LASTPIN (150 2675) $PN DP19
J 2
(140 2685);
DISPLAY 0.617021 (140 2685);
PAINT ORANGE (140 2685);
FORCEPROP 2 LASTPIN (150 2625) $PN DN8
J 2
(140 2635);
DISPLAY 0.617021 (140 2635);
PAINT ORANGE (140 2635);
FORCEPROP 2 LASTPIN (150 2575) $PN DM17
J 2
(140 2585);
DISPLAY 0.617021 (140 2585);
PAINT ORANGE (140 2585);
FORCEPROP 2 LASTPIN (150 2525) $PN DJ16
J 2
(140 2535);
DISPLAY 0.617021 (140 2535);
PAINT ORANGE (140 2535);
FORCEPROP 2 LASTPIN (150 2475) $PN H13
J 2
(140 2485);
DISPLAY 0.617021 (140 2485);
PAINT ORANGE (140 2485);
FORCEPROP 2 LASTPIN (150 2425) $PN J10
J 2
(140 2435);
DISPLAY 0.617021 (140 2435);
PAINT ORANGE (140 2435);
FORCEPROP 2 LASTPIN (150 2375) $PN L14
J 2
(140 2385);
DISPLAY 0.617021 (140 2385);
PAINT ORANGE (140 2385);
FORCEPROP 2 LASTPIN (150 2325) $PN L16
J 2
(140 2335);
DISPLAY 0.617021 (140 2335);
PAINT ORANGE (140 2335);
FORCEPROP 2 LASTPIN (150 2275) $PN DH7
J 2
(140 2285);
DISPLAY 0.617021 (140 2285);
PAINT ORANGE (140 2285);
FORCEPROP 2 LASTPIN (150 2225) $PN DG8
J 2
(140 2235);
DISPLAY 0.617021 (140 2235);
PAINT ORANGE (140 2235);
FORCEPROP 2 LASTPIN (150 2175) $PN M11
J 2
(140 2185);
DISPLAY 0.617021 (140 2185);
PAINT ORANGE (140 2185);
FORCEPROP 2 LASTPIN (150 2125) $PN M21
J 2
(140 2135);
DISPLAY 0.617021 (140 2135);
PAINT ORANGE (140 2135);
FORCEPROP 2 LASTPIN (150 2075) $PN P5
J 2
(140 2085);
DISPLAY 0.617021 (140 2085);
PAINT ORANGE (140 2085);
FORCEPROP 2 LASTPIN (150 2025) $PN T3
J 2
(140 2035);
DISPLAY 0.617021 (140 2035);
PAINT ORANGE (140 2035);
FORCEPROP 2 LASTPIN (150 1975) $PN U14
J 2
(140 1985);
DISPLAY 0.617021 (140 1985);
PAINT ORANGE (140 1985);
FORCEPROP 2 LASTPIN (150 1925) $PN DF21
J 2
(140 1935);
DISPLAY 0.617021 (140 1935);
PAINT ORANGE (140 1935);
FORCEPROP 2 LASTPIN (150 1875) $PN W4
J 2
(140 1885);
DISPLAY 0.617021 (140 1885);
PAINT ORANGE (140 1885);
FORCEPROP 2 LASTPIN (150 1825) $PN W6
J 2
(140 1835);
DISPLAY 0.617021 (140 1835);
PAINT ORANGE (140 1835);
FORCEPROP 2 LASTPIN (150 1775) $PN AA10
J 2
(140 1785);
DISPLAY 0.617021 (140 1785);
PAINT ORANGE (140 1785);
FORCEPROP 2 LASTPIN (150 1725) $PN AC20
J 2
(140 1735);
DISPLAY 0.617021 (140 1735);
PAINT ORANGE (140 1735);
FORCEPROP 2 LASTPIN (150 1675) $PN AC4
J 2
(140 1685);
DISPLAY 0.617021 (140 1685);
PAINT ORANGE (140 1685);
FORCEPROP 2 LASTPIN (150 1625) $PN AH9
J 2
(140 1635);
DISPLAY 0.617021 (140 1635);
PAINT ORANGE (140 1635);
FORCEPROP 2 LASTPIN (150 1575) $PN DF13
J 2
(140 1585);
DISPLAY 0.617021 (140 1585);
PAINT ORANGE (140 1585);
FORCEPROP 2 LASTPIN (150 1525) $PN AN10
J 2
(140 1535);
DISPLAY 0.617021 (140 1535);
PAINT ORANGE (140 1535);
FORCEPROP 2 LASTPIN (150 1475) $PN DD7
J 2
(140 1485);
DISPLAY 0.617021 (140 1485);
PAINT ORANGE (140 1485);
FORCEPROP 2 LASTPIN (150 1425) $PN AT11
J 2
(140 1435);
DISPLAY 0.617021 (140 1435);
PAINT ORANGE (140 1435);
FORCEPROP 2 LASTPIN (150 1375) $PN AW6
J 2
(140 1385);
DISPLAY 0.617021 (140 1385);
PAINT ORANGE (140 1385);
FORCEPROP 2 LASTPIN (150 1325) $PN AY11
J 2
(140 1335);
DISPLAY 0.617021 (140 1335);
PAINT ORANGE (140 1335);
FORCEPROP 2 LASTPIN (150 1275) $PN BA24
J 2
(140 1285);
DISPLAY 0.617021 (140 1285);
PAINT ORANGE (140 1285);
FORCEPROP 2 LASTPIN (150 1225) $PN BB5
J 2
(140 1235);
DISPLAY 0.617021 (140 1235);
PAINT ORANGE (140 1235);
FORCEPROP 2 LASTPIN (150 1175) $PN DA14
J 2
(140 1185);
DISPLAY 0.617021 (140 1185);
PAINT ORANGE (140 1185);
FORCEPROP 2 LASTPIN (150 1125) $PN BF23
J 2
(140 1135);
DISPLAY 0.617021 (140 1135);
PAINT ORANGE (140 1135);
FORCEPROP 2 LASTPIN (150 1075) $PN BJ24
J 2
(140 1085);
DISPLAY 0.617021 (140 1085);
PAINT ORANGE (140 1085);
FORCEPROP 2 LASTPIN (150 1025) $PN BP25
J 2
(140 1035);
DISPLAY 0.617021 (140 1035);
PAINT ORANGE (140 1035);
FORCEPROP 2 LASTPIN (1950 1175) $PN CB13
J 0
(1960 1185);
DISPLAY 0.617021 (1960 1185);
PAINT ORANGE (1960 1185);
FORCEPROP 2 LASTPIN (1950 1125) $PN CB17
J 0
(1960 1135);
DISPLAY 0.617021 (1960 1135);
PAINT ORANGE (1960 1135);
FORCEPROP 2 LASTPIN (1950 1075) $PN CD9
J 0
(1960 1085);
DISPLAY 0.617021 (1960 1085);
PAINT ORANGE (1960 1085);
FORCEPROP 2 LASTPIN (1950 1025) $PN CE18
J 0
(1960 1035);
DISPLAY 0.617021 (1960 1035);
PAINT ORANGE (1960 1035);
FORCEPROP 2 LASTPIN (1950 975) $PN D7
J 0
(1960 985);
DISPLAY 0.617021 (1960 985);
PAINT ORANGE (1960 985);
FORCEPROP 2 LASTPIN (1950 925) $PN CH9
J 0
(1960 935);
DISPLAY 0.617021 (1960 935);
PAINT ORANGE (1960 935);
FORCEPROP 2 LASTPIN (1950 825) $PN CV7
J 0
(1960 835);
DISPLAY 0.617021 (1960 835);
PAINT ORANGE (1960 835);
FORCEPROP 2 LASTPIN (1950 775) $PN CK5
J 0
(1960 785);
DISPLAY 0.617021 (1960 785);
PAINT ORANGE (1960 785);
FORCEPROP 2 LASTPIN (1950 725) $PN CL12
J 0
(1960 735);
DISPLAY 0.617021 (1960 735);
PAINT ORANGE (1960 735);
FORCEPROP 2 LASTPIN (1950 675) $PN CM15
J 0
(1960 685);
DISPLAY 0.617021 (1960 685);
PAINT ORANGE (1960 685);
FORCEPROP 2 LASTPIN (1950 1275) $PN CY55
J 0
(1960 1285);
DISPLAY 0.617021 (1960 1285);
PAINT ORANGE (1960 1285);
FORCEPROP 2 LASTPIN (1950 1775) $PN A8
J 0
(1960 1785);
DISPLAY 0.617021 (1960 1785);
PAINT ORANGE (1960 1785);
FORCEPROP 2 LASTPIN (1950 1725) $PN A10
J 0
(1960 1735);
DISPLAY 0.617021 (1960 1735);
PAINT ORANGE (1960 1735);
FORCEPROP 2 LASTPIN (1950 1675) $PN A12
J 0
(1960 1685);
DISPLAY 0.617021 (1960 1685);
PAINT ORANGE (1960 1685);
FORCEPROP 2 LASTPIN (1950 1625) $PN B11
J 0
(1960 1635);
DISPLAY 0.617021 (1960 1635);
PAINT ORANGE (1960 1635);
FORCEPROP 2 LASTPIN (1950 2675) $PN BM11
J 0
(1960 2685);
DISPLAY 0.617021 (1960 2685);
PAINT ORANGE (1960 2685);
FORCEPROP 2 LASTPIN (1950 2625) $PN BN12
J 0
(1960 2635);
DISPLAY 0.617021 (1960 2635);
PAINT ORANGE (1960 2635);
FORCEPROP 2 LASTPIN (1950 2575) $PN BN14
J 0
(1960 2585);
DISPLAY 0.617021 (1960 2585);
PAINT ORANGE (1960 2585);
FORCEPROP 2 LASTPIN (1950 2525) $PN BP11
J 0
(1960 2535);
DISPLAY 0.617021 (1960 2535);
PAINT ORANGE (1960 2535);
FORCEPROP 2 LASTPIN (1950 2475) $PN BP13
J 0
(1960 2485);
DISPLAY 0.617021 (1960 2485);
PAINT ORANGE (1960 2485);
FORCEPROP 2 LASTPIN (1950 2425) $PN BP15
J 0
(1960 2435);
DISPLAY 0.617021 (1960 2435);
PAINT ORANGE (1960 2435);
FORCEPROP 2 LASTPIN (1950 2325) $PN BR12
J 0
(1960 2335);
DISPLAY 0.617021 (1960 2335);
PAINT ORANGE (1960 2335);
FORCEPROP 2 LASTPIN (1950 2275) $PN BR14
J 0
(1960 2285);
DISPLAY 0.617021 (1960 2285);
PAINT ORANGE (1960 2285);
FORCEPROP 2 LASTPIN (1950 2225) $PN BT11
J 0
(1960 2235);
DISPLAY 0.617021 (1960 2235);
PAINT ORANGE (1960 2235);
FORCEPROP 2 LASTPIN (1950 2175) $PN BT13
J 0
(1960 2185);
DISPLAY 0.617021 (1960 2185);
PAINT ORANGE (1960 2185);
FORCEPROP 2 LASTPIN (1950 2125) $PN BT15
J 0
(1960 2135);
DISPLAY 0.617021 (1960 2135);
PAINT ORANGE (1960 2135);
FORCEPROP 2 LASTPIN (1950 2075) $PN BU12
J 0
(1960 2085);
DISPLAY 0.617021 (1960 2085);
PAINT ORANGE (1960 2085);
FORCEPROP 2 LASTPIN (1950 2025) $PN BU14
J 0
(1960 2035);
DISPLAY 0.617021 (1960 2035);
PAINT ORANGE (1960 2035);
FORCEPROP 2 LASTPIN (1950 1975) $PN BV11
J 0
(1960 1985);
DISPLAY 0.617021 (1960 1985);
PAINT ORANGE (1960 1985);
FORCEPROP 2 LASTPIN (1950 1925) $PN BV13
J 0
(1960 1935);
DISPLAY 0.617021 (1960 1935);
PAINT ORANGE (1960 1935);
FORCEPROP 2 LASTPIN (1950 1875) $PN BV15
J 0
(1960 1885);
DISPLAY 0.617021 (1960 1885);
PAINT ORANGE (1960 1885);
FORCEPROP 2 LASTPIN (1950 1525) $PN BY27
J 0
(1960 1535);
DISPLAY 0.617021 (1960 1535);
PAINT ORANGE (1960 1535);
FORCEPROP 2 LASTPIN (1950 1475) $PN BV27
J 0
(1960 1485);
DISPLAY 0.617021 (1960 1485);
PAINT ORANGE (1960 1485);
FORCEPROP 2 LASTPIN (1950 1425) $PN BU26
J 0
(1960 1435);
DISPLAY 0.617021 (1960 1435);
PAINT ORANGE (1960 1435);
FORCEPROP 2 LASTPIN (1950 1375) $PN BT27
J 0
(1960 1385);
DISPLAY 0.617021 (1960 1385);
PAINT ORANGE (1960 1385);
FORCEPROP 2 LASTPIN (1950 3375) $PN BD13
J 0
(1960 3385);
DISPLAY 0.617021 (1960 3385);
PAINT ORANGE (1960 3385);
FORCEPROP 2 LASTPIN (1950 3325) $PN BE12
J 0
(1960 3335);
DISPLAY 0.617021 (1960 3335);
PAINT ORANGE (1960 3335);
FORCEPROP 2 LASTPIN (1950 3275) $PN BE14
J 0
(1960 3285);
DISPLAY 0.617021 (1960 3285);
PAINT ORANGE (1960 3285);
FORCEPROP 2 LASTPIN (1950 3225) $PN BF11
J 0
(1960 3235);
DISPLAY 0.617021 (1960 3235);
PAINT ORANGE (1960 3235);
FORCEPROP 2 LASTPIN (1950 3175) $PN BF13
J 0
(1960 3185);
DISPLAY 0.617021 (1960 3185);
PAINT ORANGE (1960 3185);
FORCEPROP 2 LASTPIN (1950 3125) $PN BG12
J 0
(1960 3135);
DISPLAY 0.617021 (1960 3135);
PAINT ORANGE (1960 3135);
FORCEPROP 2 LASTPIN (1950 3075) $PN BG14
J 0
(1960 3085);
DISPLAY 0.617021 (1960 3085);
PAINT ORANGE (1960 3085);
FORCEPROP 2 LASTPIN (1950 3025) $PN BH13
J 0
(1960 3035);
DISPLAY 0.617021 (1960 3035);
PAINT ORANGE (1960 3035);
FORCEPROP 2 LASTPIN (1950 2975) $PN BJ12
J 0
(1960 2985);
DISPLAY 0.617021 (1960 2985);
PAINT ORANGE (1960 2985);
FORCEPROP 2 LASTPIN (1950 2925) $PN BJ14
J 0
(1960 2935);
DISPLAY 0.617021 (1960 2935);
PAINT ORANGE (1960 2935);
FORCEPROP 2 LASTPIN (1950 2875) $PN BK13
J 0
(1960 2885);
DISPLAY 0.617021 (1960 2885);
PAINT ORANGE (1960 2885);
FORCEPROP 2 LASTPIN (1950 2825) $PN BK15
J 0
(1960 2835);
DISPLAY 0.617021 (1960 2835);
PAINT ORANGE (1960 2835);
FORCEPROP 2 LASTPIN (1950 2775) $PN BL14
J 0
(1960 2785);
DISPLAY 0.617021 (1960 2785);
PAINT ORANGE (1960 2785);
FORCEPROP 1 LAST PACK_TYPE BGA1
J 0
(200 5025);
PAINT SKYBLUE (200 5025);
DISPLAY INVISIBLE (200 5025);
FORCEPROP 2 LAST SEC_TYPE BGA1
J 0
(200 5025);
DISPLAY 1.021277 (200 5025);
PAINT ORANGE (200 5025);
DISPLAY INVISIBLE (200 5025);
FORCEPROP 2 LAST CDS_LIB chpset_lib
J 0
(1050 2725);
PAINT ORANGE (1050 2725);
DISPLAY INVISIBLE (1050 2725);
FORCEPROP 2 LAST SEC 21
J 0
(200 5025);
DISPLAY 0.680851 (200 5025);
PAINT MONO (200 5025);
DISPLAY INVISIBLE (200 5025);
FORCEPROP 2 LAST CDS_LOCATION U5D1
J 0
(200 4975);
DISPLAY 0.617021 (200 4975);
PAINT AQUA (200 4975);
DISPLAY INVISIBLE (200 4975);
FORCEPROP 1 LAST PATH I34
J 0
(1050 4925);
PAINT GREEN (1050 4925);
DISPLAY INVISIBLE (1050 4925);
FORCEPROP 0 LAST ROOM CPU0
J 0
(200 5075);
DISPLAY 1.021277 (200 5075);
PAINT ORANGE (200 5075);
DISPLAY INVISIBLE (200 5075);
FORCEADD VCC_CORE..1
(3550 1600);
FORCEPROP 3 LASTPIN (3550 1550) SIG_NAME P1V8_MCP_CPU0\g
J 0
(3560 1560);
DISPLAY 0.659574 (3560 1560);
PAINT MONO (3560 1560);
DISPLAY INVISIBLE (3560 1560);
FORCEPROP 1 LAST HDL_POWER P1V8_MCP_CPU0
J 1
(3550 1650);
DISPLAY 0.617021 (3550 1650);
PAINT GREEN (3550 1650);
FORCEPROP 0 LAST VOLTAGE +1.8V
J 0
(3550 1750);
DISPLAY 1.021277 (3550 1750);
PAINT SKYBLUE (3550 1750);
DISPLAY INVISIBLE (3550 1750);
FORCEPROP 2 LAST CDS_LIB mstr_symbols
J 0
(3550 1600);
PAINT ORANGE (3550 1600);
DISPLAY INVISIBLE (3550 1600);
FORCEPROP 1 LAST PATH I35
J 0
(3600 1625);
DISPLAY 0.872340 (3600 1625);
PAINT AQUA (3600 1625);
DISPLAY INVISIBLE (3600 1625);
FORCEADD P3V3_STBY..1
(2650 1350);
FORCEPROP 3 LASTPIN (2650 1300) SIG_NAME P3V3_STBY\g
J 0
(2660 1310);
DISPLAY 0.659574 (2660 1310);
PAINT MONO (2660 1310);
DISPLAY INVISIBLE (2660 1310);
FORCEPROP 1 LAST VOLTAGE 3.3V
J 0
(2605 1307);
DISPLAY 0.340426 (2605 1307);
PAINT SKYBLUE (2605 1307);
DISPLAY INVISIBLE (2605 1307);
FORCEPROP 2 LAST CDS_LIB mstr_symbols
J 0
(2650 1350);
PAINT ORANGE (2650 1350);
DISPLAY INVISIBLE (2650 1350);
FORCEPROP 1 LAST SIZE 1B
J 0
(2695 1372);
DISPLAY 0.340426 (2695 1372);
PAINT GREEN (2695 1372);
DISPLAY INVISIBLE (2695 1372);
FORCEPROP 1 LAST BODY_TYPE PLUMBING
J 0
(2605 1307);
DISPLAY 0.340426 (2605 1307);
PAINT GREEN (2605 1307);
DISPLAY INVISIBLE (2605 1307);
FORCEPROP 1 LAST PATH I36
J 0
(2695 1352);
DISPLAY 0.340426 (2695 1352);
PAINT GREEN (2695 1352);
DISPLAY INVISIBLE (2695 1352);
FORCEPROP 1 LAST HDL_POWER P3V3_STBY
J 0
(2350 1225);
DISPLAY 0.872340 (2350 1225);
PAINT ORANGE (2350 1225);
DISPLAY INVISIBLE (2350 1225);
FORCEADD DESIGN_NOTE..1
(-1525 900);
FORCEPROP 0 LAST L1 CPU SYMBOLS 1-30 ARE PRELIMINARY AND SUBJECT TO CHANGE
J 0
(-1725 775);
DISPLAY 1.021277 (-1725 775);
PAINT ORANGE (-1725 775);
FORCEPROP 2 LAST CDS_LIB mstr_symbols
J 0
(-1525 900);
PAINT ORANGE (-1525 900);
DISPLAY INVISIBLE (-1525 900);
FORCEPROP 1 LAST COMMENT_BODY TRUE
J 0
(-1500 1000);
DISPLAY 0.978723 (-1500 1000);
PAINT ORANGE (-1500 1000);
DISPLAY INVISIBLE (-1500 1000);
FORCEADD INTEL_CORP_BPAGE..1
(4125 150);
FORCEPROP 1 LAST CDS_CON_LAST_MODIFIED Tue Dec 01 11:51:23 2015
J 0
(2700 475);
DISPLAY 1.340426 (2700 475);
PAINT GREEN (2700 475);
DISPLAY INVISIBLE (2700 475);
FORCEPROP 1 LAST CUSTOM_TXT_CDS <CURRENT_DESIGN_SHEET> OF <TOTAL_DESIGN_SHEETS>
J 0
(3625 175);
PAINT GREEN (3625 175);
FORCEPROP 1 LAST CUSTOM_TXT_CDS <CON_LAST_MODIFIED>
J 0
(2200 500);
PAINT GREEN (2200 500);
FORCEPROP 2 LAST CUSTOM_TXT_CDS <XR_PAGE_TITLE>
J 0
(-3765 5400);
DISPLAY 0.638298 (-3765 5400);
PAINT PINK (-3765 5400);
DISPLAY INVISIBLE (-3765 5400);
FORCEPROP 1 LAST SCH_ADDRESS3 Santa Clara, CA 95052-8119
J 0
(150 175);
DISPLAY 0.617021 (150 175);
PAINT GREEN (150 175);
FORCEPROP 1 LAST SCH_ADDRESS2 P.O. BOX 58119
J 0
(150 225);
DISPLAY 0.617021 (150 225);
PAINT GREEN (150 225);
FORCEPROP 1 LAST SCH_ADDRESS1 2200 Mission College Blvd.
J 0
(150 275);
DISPLAY 0.617021 (150 275);
PAINT GREEN (150 275);
FORCEPROP 1 LAST SCH_TITLE SKYLAKE - SKT0 - 18 OF 21
J 0
(-3825 200);
DISPLAY 1.212766 (-3825 200);
PAINT GREEN (-3825 200);
FORCEPROP 1 LAST SCH_NUMBER H4694802
J 0
(2825 300);
DISPLAY 1.212766 (2825 300);
PAINT YELLOW (2825 300);
FORCEPROP 1 LAST SCH_DEPT BESD
J 1
(-325 250);
DISPLAY 1.212766 (-325 250);
PAINT YELLOW (-325 250);
FORCEPROP 1 LAST SCH_REV 2.420
J 0
(3875 300);
DISPLAY 0.978723 (3875 300);
PAINT YELLOW (3875 300);
FORCEPROP 2 LAST CDS_LIB mstr_symbols
J 0
(4125 150);
PAINT ORANGE (4125 150);
DISPLAY INVISIBLE (4125 150);
FORCEPROP 2 LAST PAGE_BORDER TRUE
J 0
(-3765 5400);
DISPLAY 0.851064 (-3765 5400);
PAINT PINK (-3765 5400);
DISPLAY INVISIBLE (-3765 5400);
FORCEPROP 1 LAST COMMENT_BODY TRUE
J 0
(4137 162);
DISPLAY 0.638298 (4137 162);
PAINT GREEN (4137 162);
DISPLAY INVISIBLE (4137 162);
FORCEPROP 2 LAST CDS_XR_PAGE_TITLE CR-38 : @BASEBOARD_FAB2_LIB.BASEBOARD_FAB2(SCH_1):PAGE38
J 0
(-3765 5400);
DISPLAY 0.638298 (-3765 5400);
PAINT PINK (-3765 5400);
DISPLAY INVISIBLE (-3765 5400);
WIRE 16 -1 (-3075 1350)(-2800 1350);
WIRE 16 -1 (-3075 1400)(-3075 1350);
WIRE 16 -1 (-3075 1400)(-2800 1400);
WIRE 16 -1 (-3075 1450)(-3075 1400);
WIRE 16 -1 (-3075 1450)(-2800 1450);
WIRE 16 -1 (-3075 1550)(-3075 1450);
WIRE 16 -1 (-3075 1550)(-2800 1550);
WIRE 16 -1 (-3075 1600)(-3075 1550);
WIRE 16 -1 (-3075 1600)(-2800 1600);
WIRE 16 -1 (-3075 1650)(-3075 1600);
WIRE 16 -1 (-3075 1650)(-2800 1650);
WIRE 16 -1 (-3075 1700)(-3075 1650);
WIRE 16 -1 (-3075 1700)(-2800 1700);
WIRE 16 -1 (-3075 1750)(-3075 1700);
WIRE 16 -1 (-3075 1750)(-2800 1750);
WIRE 16 -1 (-3075 1800)(-3075 1750);
WIRE 16 -1 (-3075 1800)(-2800 1800);
WIRE 16 -1 (-3075 1850)(-3075 1800);
WIRE 16 -1 (-3075 1850)(-2800 1850);
WIRE 16 -1 (-3075 1900)(-3075 1850);
WIRE 16 -1 (-3075 1900)(-2800 1900);
WIRE 16 -1 (-3075 1950)(-3075 1900);
WIRE 16 -1 (-3075 1950)(-2800 1950);
WIRE 16 -1 (-3075 2000)(-3075 1950);
WIRE 16 -1 (-3075 2050)(-3075 2000);
WIRE 16 -1 (-3075 2000)(-2800 2000);
WIRE 16 -1 (-3075 2050)(-2800 2050);
WIRE 16 -1 (-3075 2100)(-3075 2050);
WIRE 16 -1 (-3075 2100)(-2800 2100);
WIRE 16 -1 (-3075 2150)(-3075 2100);
WIRE 16 -1 (-3075 2150)(-2800 2150);
WIRE 16 -1 (-3075 2200)(-3075 2150);
WIRE 16 -1 (-3075 2200)(-2800 2200);
WIRE 16 -1 (-3075 2250)(-3075 2200);
WIRE 16 -1 (-3075 2250)(-2800 2250);
WIRE 16 -1 (-3075 2300)(-3075 2250);
WIRE 16 -1 (-3075 2300)(-2800 2300);
WIRE 16 -1 (-3075 2350)(-3075 2300);
WIRE 16 -1 (-3075 2350)(-2800 2350);
WIRE 16 -1 (-3075 2400)(-3075 2350);
WIRE 16 -1 (-3075 2400)(-2800 2400);
WIRE 16 -1 (-3075 2450)(-3075 2400);
WIRE 16 -1 (-3075 2450)(-2800 2450);
WIRE 16 -1 (-3075 2500)(-3075 2450);
WIRE 16 -1 (-3075 2500)(-2800 2500);
WIRE 16 -1 (-3075 2550)(-3075 2500);
WIRE 16 -1 (-3075 2550)(-2800 2550);
WIRE 16 -1 (-3075 2600)(-3075 2550);
WIRE 16 -1 (-3075 2600)(-2800 2600);
WIRE 16 -1 (-3075 2650)(-3075 2600);
WIRE 16 -1 (-3075 2650)(-2800 2650);
WIRE 16 -1 (-3075 2700)(-3075 2650);
WIRE 16 -1 (-3075 2700)(-2800 2700);
WIRE 16 -1 (-3075 2750)(-3075 2700);
WIRE 16 -1 (-3075 2750)(-2800 2750);
WIRE 16 -1 (-3075 2800)(-3075 2750);
WIRE 16 -1 (-3075 2800)(-2800 2800);
WIRE 16 -1 (-3075 2850)(-3075 2800);
WIRE 16 -1 (-3075 2850)(-2800 2850);
WIRE 16 -1 (-3075 2900)(-3075 2850);
WIRE 16 -1 (-3075 2900)(-2800 2900);
WIRE 16 -1 (-3075 2950)(-3075 2900);
WIRE 16 -1 (-3075 2950)(-2800 2950);
WIRE 16 -1 (-3075 3000)(-3075 2950);
WIRE 16 -1 (-3075 3000)(-2800 3000);
WIRE 16 -1 (-3075 3050)(-3075 3000);
WIRE 16 -1 (-3075 3050)(-2800 3050);
WIRE 16 -1 (-3075 3100)(-3075 3050);
WIRE 16 -1 (-3075 3100)(-2800 3100);
WIRE 16 -1 (-3075 3150)(-3075 3100);
WIRE 16 -1 (-3075 3150)(-2800 3150);
WIRE 16 -1 (-3075 3200)(-3075 3150);
WIRE 16 -1 (-3075 3200)(-2800 3200);
WIRE 16 -1 (-3075 3250)(-3075 3200);
WIRE 16 -1 (-3075 3250)(-2800 3250);
WIRE 16 -1 (-3075 3300)(-3075 3250);
WIRE 16 -1 (-3075 3300)(-2800 3300);
WIRE 16 -1 (-3075 3350)(-3075 3300);
WIRE 16 -1 (-3075 3350)(-2800 3350);
WIRE 16 -1 (-3075 3400)(-3075 3350);
WIRE 16 -1 (-3075 3400)(-2800 3400);
WIRE 16 -1 (-3075 3450)(-3075 3400);
WIRE 16 -1 (-3075 3450)(-2800 3450);
WIRE 16 -1 (-3075 3500)(-3075 3450);
WIRE 16 -1 (-3075 3500)(-2800 3500);
WIRE 16 -1 (-3075 3550)(-3075 3500);
WIRE 16 -1 (-3075 3550)(-2800 3550);
WIRE 16 -1 (-3075 3600)(-3075 3550);
WIRE 16 -1 (-3075 3600)(-2800 3600);
WIRE 16 -1 (-3075 3650)(-3075 3600);
WIRE 16 -1 (-3075 3650)(-2800 3650);
WIRE 16 -1 (-3075 3700)(-3075 3650);
WIRE 16 -1 (-3075 3700)(-2800 3700);
WIRE 16 -1 (-3075 3750)(-3075 3700);
WIRE 16 -1 (-3075 3750)(-2800 3750);
WIRE 16 -1 (-3075 3800)(-3075 3750);
WIRE 16 -1 (-3075 3800)(-2800 3800);
WIRE 16 -1 (-3075 3850)(-3075 3800);
WIRE 16 -1 (-3075 3850)(-2800 3850);
WIRE 16 -1 (-3075 3900)(-3075 3850);
WIRE 16 -1 (-3075 3900)(-2800 3900);
WIRE 16 -1 (-3075 3950)(-3075 3900);
WIRE 16 -1 (-3075 4350)(-3075 3950);
WIRE 16 -1 (-3075 3950)(-2800 3950);
WIRE 16 -1 (-800 1450)(-800 1400);
WIRE 16 -1 (-800 1550)(-800 1450);
WIRE 16 -1 (-800 1450)(-1100 1450);
WIRE 16 -1 (-800 1400)(-1100 1400);
WIRE 16 -1 (-800 1600)(-800 1550);
WIRE 16 -1 (-800 1550)(-1100 1550);
WIRE 16 -1 (-800 1650)(-800 1600);
WIRE 16 -1 (-800 1600)(-1100 1600);
WIRE 16 -1 (-800 1700)(-800 1650);
WIRE 16 -1 (-800 1650)(-1100 1650);
WIRE 16 -1 (-800 1750)(-800 1700);
WIRE 16 -1 (-800 1700)(-1100 1700);
WIRE 16 -1 (-800 1800)(-800 1750);
WIRE 16 -1 (-800 1750)(-1100 1750);
WIRE 16 -1 (-800 1850)(-800 1800);
WIRE 16 -1 (-800 1800)(-1100 1800);
WIRE 16 -1 (-800 1900)(-800 1850);
WIRE 16 -1 (-800 1850)(-1100 1850);
WIRE 16 -1 (-800 1950)(-800 1900);
WIRE 16 -1 (-800 1900)(-1100 1900);
WIRE 16 -1 (-800 2000)(-800 1950);
WIRE 16 -1 (-800 1950)(-1100 1950);
WIRE 16 -1 (-800 2050)(-800 2000);
WIRE 16 -1 (-800 2000)(-1100 2000);
WIRE 16 -1 (-800 2100)(-800 2050);
WIRE 16 -1 (-800 2050)(-1100 2050);
WIRE 16 -1 (-800 2150)(-800 2100);
WIRE 16 -1 (-800 2100)(-1100 2100);
WIRE 16 -1 (-800 2200)(-800 2150);
WIRE 16 -1 (-800 2150)(-1100 2150);
WIRE 16 -1 (-800 2250)(-800 2200);
WIRE 16 -1 (-800 2200)(-1100 2200);
WIRE 16 -1 (-800 2300)(-800 2250);
WIRE 16 -1 (-800 2250)(-1100 2250);
WIRE 16 -1 (-800 2350)(-800 2300);
WIRE 16 -1 (-800 2300)(-1100 2300);
WIRE 16 -1 (-800 2400)(-800 2350);
WIRE 16 -1 (-800 2350)(-1100 2350);
WIRE 16 -1 (-800 2450)(-800 2400);
WIRE 16 -1 (-800 2400)(-1100 2400);
WIRE 16 -1 (-800 2500)(-800 2450);
WIRE 16 -1 (-800 2450)(-1100 2450);
WIRE 16 -1 (-800 2550)(-800 2500);
WIRE 16 -1 (-800 2500)(-1100 2500);
WIRE 16 -1 (-800 2600)(-800 2550);
WIRE 16 -1 (-800 2550)(-1100 2550);
WIRE 16 -1 (-800 2650)(-800 2600);
WIRE 16 -1 (-800 2600)(-1100 2600);
WIRE 16 -1 (-800 2700)(-800 2650);
WIRE 16 -1 (-800 2650)(-1100 2650);
WIRE 16 -1 (-800 2750)(-800 2700);
WIRE 16 -1 (-800 2700)(-1100 2700);
WIRE 16 -1 (-800 2800)(-800 2750);
WIRE 16 -1 (-800 2750)(-1100 2750);
WIRE 16 -1 (-800 2850)(-800 2800);
WIRE 16 -1 (-800 2800)(-1100 2800);
WIRE 16 -1 (-800 2900)(-800 2850);
WIRE 16 -1 (-800 2850)(-1100 2850);
WIRE 16 -1 (-800 2950)(-800 2900);
WIRE 16 -1 (-800 2900)(-1100 2900);
WIRE 16 -1 (-800 3000)(-800 2950);
WIRE 16 -1 (-800 2950)(-1100 2950);
WIRE 16 -1 (-800 3050)(-800 3000);
WIRE 16 -1 (-800 3000)(-1100 3000);
WIRE 16 -1 (-800 3100)(-800 3050);
WIRE 16 -1 (-800 3050)(-1100 3050);
WIRE 16 -1 (-800 3150)(-800 3100);
WIRE 16 -1 (-800 3100)(-1100 3100);
WIRE 16 -1 (-800 3200)(-800 3150);
WIRE 16 -1 (-800 3150)(-1100 3150);
WIRE 16 -1 (-800 3250)(-800 3200);
WIRE 16 -1 (-800 3200)(-1100 3200);
WIRE 16 -1 (-800 3300)(-800 3250);
WIRE 16 -1 (-800 3250)(-1100 3250);
WIRE 16 -1 (-800 3350)(-800 3300);
WIRE 16 -1 (-800 3300)(-1100 3300);
WIRE 16 -1 (-800 3400)(-800 3350);
WIRE 16 -1 (-800 3350)(-1100 3350);
WIRE 16 -1 (-800 3450)(-800 3400);
WIRE 16 -1 (-800 3400)(-1100 3400);
WIRE 16 -1 (-800 3500)(-800 3450);
WIRE 16 -1 (-800 3450)(-1100 3450);
WIRE 16 -1 (-800 3550)(-800 3500);
WIRE 16 -1 (-800 3500)(-1100 3500);
WIRE 16 -1 (-800 3600)(-800 3550);
WIRE 16 -1 (-800 3550)(-1100 3550);
WIRE 16 -1 (-800 3650)(-800 3600);
WIRE 16 -1 (-800 3600)(-1100 3600);
WIRE 16 -1 (-800 3700)(-800 3650);
WIRE 16 -1 (-800 3650)(-1100 3650);
WIRE 16 -1 (-800 3750)(-800 3700);
WIRE 16 -1 (-800 3700)(-1100 3700);
WIRE 16 -1 (-800 3800)(-800 3750);
WIRE 16 -1 (-800 3750)(-1100 3750);
WIRE 16 -1 (-800 3850)(-800 3800);
WIRE 16 -1 (-800 3800)(-1100 3800);
WIRE 16 -1 (-800 3900)(-800 3850);
WIRE 16 -1 (-800 3850)(-1100 3850);
WIRE 16 -1 (-800 3950)(-800 3900);
WIRE 16 -1 (-800 3900)(-1100 3900);
WIRE 16 -1 (-800 3950)(-800 4350);
WIRE 16 -1 (-800 3950)(-1100 3950);
WIRE 16 -1 (150 1025)(-250 1025);
WIRE 16 -1 (-250 1075)(-250 1025);
WIRE 16 -1 (150 1075)(-250 1075);
WIRE 16 -1 (-250 1125)(-250 1075);
WIRE 16 -1 (150 1125)(-250 1125);
WIRE 16 -1 (-250 1175)(-250 1125);
WIRE 16 -1 (150 1175)(-250 1175);
WIRE 16 -1 (-250 1225)(-250 1175);
WIRE 16 -1 (150 1225)(-250 1225);
WIRE 16 -1 (-250 1275)(-250 1225);
WIRE 16 -1 (150 1275)(-250 1275);
WIRE 16 -1 (-250 1325)(-250 1275);
WIRE 16 -1 (150 1325)(-250 1325);
WIRE 16 -1 (-250 1375)(-250 1325);
WIRE 16 -1 (150 1375)(-250 1375);
WIRE 16 -1 (-250 1425)(-250 1375);
WIRE 16 -1 (150 1425)(-250 1425);
WIRE 16 -1 (-250 1475)(-250 1425);
WIRE 16 -1 (150 1475)(-250 1475);
WIRE 16 -1 (-250 1525)(-250 1475);
WIRE 16 -1 (150 1525)(-250 1525);
WIRE 16 -1 (-250 1575)(-250 1525);
WIRE 16 -1 (150 1575)(-250 1575);
WIRE 16 -1 (-250 1625)(-250 1575);
WIRE 16 -1 (150 1625)(-250 1625);
WIRE 16 -1 (-250 1675)(-250 1625);
WIRE 16 -1 (150 1675)(-250 1675);
WIRE 16 -1 (-250 1725)(-250 1675);
WIRE 16 -1 (150 1725)(-250 1725);
WIRE 16 -1 (-250 1775)(-250 1725);
WIRE 16 -1 (150 1775)(-250 1775);
WIRE 16 -1 (-250 1825)(-250 1775);
WIRE 16 -1 (150 1825)(-250 1825);
WIRE 16 -1 (-250 1875)(-250 1825);
WIRE 16 -1 (150 1875)(-250 1875);
WIRE 16 -1 (-250 1925)(-250 1875);
WIRE 16 -1 (150 1925)(-250 1925);
WIRE 16 -1 (-250 1975)(-250 1925);
WIRE 16 -1 (150 1975)(-250 1975);
WIRE 16 -1 (-250 2025)(-250 1975);
WIRE 16 -1 (150 2025)(-250 2025);
WIRE 16 -1 (-250 2075)(-250 2025);
WIRE 16 -1 (150 2075)(-250 2075);
WIRE 16 -1 (-250 2125)(-250 2075);
WIRE 16 -1 (150 2125)(-250 2125);
WIRE 16 -1 (-250 2175)(-250 2125);
WIRE 16 -1 (150 2175)(-250 2175);
WIRE 16 -1 (-250 2225)(-250 2175);
WIRE 16 -1 (150 2225)(-250 2225);
WIRE 16 -1 (-250 2275)(-250 2225);
WIRE 16 -1 (150 2275)(-250 2275);
WIRE 16 -1 (-250 2325)(-250 2275);
WIRE 16 -1 (150 2325)(-250 2325);
WIRE 16 -1 (-250 2375)(-250 2325);
WIRE 16 -1 (150 2375)(-250 2375);
WIRE 16 -1 (-250 2425)(-250 2375);
WIRE 16 -1 (150 2425)(-250 2425);
WIRE 16 -1 (-250 2475)(-250 2425);
WIRE 16 -1 (150 2475)(-250 2475);
WIRE 16 -1 (-250 2525)(-250 2475);
WIRE 16 -1 (150 2525)(-250 2525);
WIRE 16 -1 (-250 2575)(-250 2525);
WIRE 16 -1 (150 2575)(-250 2575);
WIRE 16 -1 (-250 2625)(-250 2575);
WIRE 16 -1 (150 2625)(-250 2625);
WIRE 16 -1 (-250 2675)(-250 2625);
WIRE 16 -1 (150 2675)(-250 2675);
WIRE 16 -1 (-250 2725)(-250 2675);
WIRE 16 -1 (150 2725)(-250 2725);
WIRE 16 -1 (-250 2775)(-250 2725);
WIRE 16 -1 (150 2775)(-250 2775);
WIRE 16 -1 (-250 2825)(-250 2775);
WIRE 16 -1 (150 2825)(-250 2825);
WIRE 16 -1 (-250 2875)(-250 2825);
WIRE 16 -1 (150 2875)(-250 2875);
WIRE 16 -1 (-250 2925)(-250 2875);
WIRE 16 -1 (150 2925)(-250 2925);
WIRE 16 -1 (-250 2975)(-250 2925);
WIRE 16 -1 (150 2975)(-250 2975);
WIRE 16 -1 (-250 3025)(-250 2975);
WIRE 16 -1 (150 3025)(-250 3025);
WIRE 16 -1 (-250 3075)(-250 3025);
WIRE 16 -1 (150 3075)(-250 3075);
WIRE 16 -1 (-250 3125)(-250 3075);
WIRE 16 -1 (150 3125)(-250 3125);
WIRE 16 -1 (-250 3175)(-250 3125);
WIRE 16 -1 (150 3175)(-250 3175);
WIRE 16 -1 (-250 3225)(-250 3175);
WIRE 16 -1 (150 3225)(-250 3225);
WIRE 16 -1 (-250 3275)(-250 3225);
WIRE 16 -1 (150 3275)(-250 3275);
WIRE 16 -1 (-250 3325)(-250 3275);
WIRE 16 -1 (150 3325)(-250 3325);
WIRE 16 -1 (-250 3375)(-250 3325);
WIRE 16 -1 (150 3375)(-250 3375);
WIRE 16 -1 (-250 3425)(-250 3375);
WIRE 16 -1 (150 3425)(-250 3425);
WIRE 16 -1 (-250 3475)(-250 3425);
WIRE 16 -1 (150 3475)(-250 3475);
WIRE 16 -1 (-250 3525)(-250 3475);
WIRE 16 -1 (150 3525)(-250 3525);
WIRE 16 -1 (-250 3575)(-250 3525);
WIRE 16 -1 (150 3575)(-250 3575);
WIRE 16 -1 (-250 3625)(-250 3575);
WIRE 16 -1 (150 3625)(-250 3625);
WIRE 16 -1 (-250 3675)(-250 3625);
WIRE 16 -1 (150 3675)(-250 3675);
WIRE 16 -1 (-250 3725)(-250 3675);
WIRE 16 -1 (150 3725)(-250 3725);
WIRE 16 -1 (-250 3775)(-250 3725);
WIRE 16 -1 (150 3775)(-250 3775);
WIRE 16 -1 (-250 3825)(-250 3775);
WIRE 16 -1 (150 3825)(-250 3825);
WIRE 16 -1 (-250 3875)(-250 3825);
WIRE 16 -1 (150 3875)(-250 3875);
WIRE 16 -1 (-250 3925)(-250 3875);
WIRE 16 -1 (150 3925)(-250 3925);
WIRE 16 -1 (-250 3975)(-250 3925);
WIRE 16 -1 (150 3975)(-250 3975);
WIRE 16 -1 (-250 4025)(-250 3975);
WIRE 16 -1 (150 4025)(-250 4025);
WIRE 16 -1 (-250 4075)(-250 4025);
WIRE 16 -1 (150 4075)(-250 4075);
WIRE 16 -1 (-250 4125)(-250 4075);
WIRE 16 -1 (150 4125)(-250 4125);
WIRE 16 -1 (-250 4175)(-250 4125);
WIRE 16 -1 (150 4175)(-250 4175);
WIRE 16 -1 (-250 4225)(-250 4175);
WIRE 16 -1 (150 4225)(-250 4225);
WIRE 16 -1 (-250 4275)(-250 4225);
WIRE 16 -1 (150 4275)(-250 4275);
WIRE 16 -1 (-250 4325)(-250 4275);
WIRE 16 -1 (150 4325)(-250 4325);
WIRE 16 -1 (-250 4375)(-250 4325);
WIRE 16 -1 (150 4375)(-250 4375);
WIRE 16 -1 (-250 4425)(-250 4375);
WIRE 16 -1 (150 4425)(-250 4425);
WIRE 16 -1 (-250 4475)(-250 4425);
WIRE 16 -1 (150 4475)(-250 4475);
WIRE 16 -1 (-250 4525)(-250 4475);
WIRE 16 -1 (150 4525)(-250 4525);
WIRE 16 -1 (-250 4575)(-250 4525);
WIRE 16 -1 (150 4575)(-250 4575);
WIRE 16 -1 (-250 4625)(-250 4575);
WIRE 16 -1 (150 4625)(-250 4625);
WIRE 16 -1 (-250 4675)(-250 4625);
WIRE 16 -1 (150 4675)(-250 4675);
WIRE 16 -1 (-250 4725)(-250 4675);
WIRE 16 -1 (150 4725)(-250 4725);
WIRE 16 -1 (-250 4825)(-250 4725);
WIRE 16 -1 (3400 1025)(3400 900);
WIRE 16 -1 (2175 725)(2175 675);
WIRE 16 -1 (2175 775)(2175 725);
WIRE 16 -1 (2175 725)(1950 725);
WIRE 16 -1 (2175 675)(1950 675);
WIRE 16 -1 (2175 825)(2175 775);
WIRE 16 -1 (2175 775)(1950 775);
WIRE 16 -1 (2175 925)(2175 825);
WIRE 16 -1 (2175 825)(1950 825);
WIRE 16 -1 (1950 925)(2175 925);
WIRE 16 -1 (2175 975)(2175 925);
WIRE 16 -1 (1950 975)(2175 975);
WIRE 16 -1 (2175 1025)(2175 975);
WIRE 16 -1 (1950 1025)(2175 1025);
WIRE 16 -1 (2175 1075)(2175 1025);
WIRE 16 -1 (1950 1075)(2175 1075);
WIRE 16 -1 (2175 1100)(2175 1075);
WIRE 16 -1 (2175 1125)(2175 1100);
WIRE 16 -1 (2900 1100)(2175 1100);
WIRE 16 -1 (2900 1175)(2900 1100);
WIRE 16 -1 (2175 1175)(2175 1125);
WIRE 16 -1 (1950 1125)(2175 1125);
WIRE 16 -1 (1950 1175)(2175 1175);
WIRE 16 -1 (1950 3475)(2150 3475);
WIRE 16 -1 (2150 3475)(2150 3525);
WIRE 16 -1 (1950 3525)(2150 3525);
WIRE 16 -1 (2150 3525)(2150 3575);
WIRE 16 -1 (1950 3575)(2150 3575);
WIRE 16 -1 (2150 3575)(2150 3625);
WIRE 16 -1 (1950 3625)(2150 3625);
WIRE 16 -1 (2150 3625)(2150 3675);
WIRE 16 -1 (1950 3675)(2150 3675);
WIRE 16 -1 (2150 3675)(2150 3725);
WIRE 16 -1 (1950 3725)(2150 3725);
WIRE 16 -1 (2150 3725)(2150 3775);
WIRE 16 -1 (1950 3775)(2150 3775);
WIRE 16 -1 (2150 3775)(2150 3825);
WIRE 16 -1 (1950 3825)(2150 3825);
WIRE 16 -1 (2150 3825)(2150 3875);
WIRE 16 -1 (1950 3875)(2150 3875);
WIRE 16 -1 (2150 3875)(2150 3925);
WIRE 16 -1 (1950 3925)(2150 3925);
WIRE 16 -1 (2150 3925)(2150 3975);
WIRE 16 -1 (1950 3975)(2150 3975);
WIRE 16 -1 (2150 3975)(2150 4025);
WIRE 16 -1 (1950 4025)(2150 4025);
WIRE 16 -1 (2150 4025)(2150 4075);
WIRE 16 -1 (1950 4075)(2150 4075);
WIRE 16 -1 (2150 4075)(2150 4125);
WIRE 16 -1 (1950 4125)(2150 4125);
WIRE 16 -1 (2150 4125)(2150 4175);
WIRE 16 -1 (1950 4175)(2150 4175);
WIRE 16 -1 (2150 4175)(2150 4225);
WIRE 16 -1 (1950 4225)(2150 4225);
WIRE 16 -1 (2150 4225)(2150 4275);
WIRE 16 -1 (1950 4275)(2150 4275);
WIRE 16 -1 (2150 4275)(2150 4325);
WIRE 16 -1 (1950 4325)(2150 4325);
WIRE 16 -1 (2150 4325)(2150 4375);
WIRE 16 -1 (1950 4375)(2150 4375);
WIRE 16 -1 (2150 4375)(2150 4425);
WIRE 16 -1 (1950 4425)(2150 4425);
WIRE 16 -1 (2150 4425)(2150 4475);
WIRE 16 -1 (1950 4475)(2150 4475);
WIRE 16 -1 (2150 4475)(2150 4525);
WIRE 16 -1 (1950 4525)(2150 4525);
WIRE 16 -1 (2150 4525)(2150 4575);
WIRE 16 -1 (1950 4575)(2150 4575);
WIRE 16 -1 (2150 4575)(2150 4625);
WIRE 16 -1 (1950 4625)(2150 4625);
WIRE 16 -1 (2150 4675)(2150 4625);
WIRE 16 -1 (1950 4675)(2150 4675);
WIRE 16 -1 (2150 4675)(2150 4725);
WIRE 16 -1 (1950 4725)(2150 4725);
WIRE 16 -1 (2150 4900)(2150 4725);
WIRE 16 -1 (1950 1875)(2150 1875);
WIRE 16 -1 (2150 1925)(2150 1875);
WIRE 16 -1 (1950 1925)(2150 1925);
WIRE 16 -1 (2150 1975)(2150 1925);
WIRE 16 -1 (1950 1975)(2150 1975);
WIRE 16 -1 (2150 2025)(2150 1975);
WIRE 16 -1 (1950 2025)(2150 2025);
WIRE 16 -1 (2150 2075)(2150 2025);
WIRE 16 -1 (1950 2075)(2150 2075);
WIRE 16 -1 (2150 2125)(2150 2075);
WIRE 16 -1 (1950 2125)(2150 2125);
WIRE 16 -1 (2150 2125)(2150 2175);
WIRE 16 -1 (2150 2225)(2150 2175);
WIRE 16 -1 (2150 2175)(1950 2175);
WIRE 16 -1 (1950 2225)(2150 2225);
WIRE 16 -1 (2150 2275)(2150 2225);
WIRE 16 -1 (1950 2275)(2150 2275);
WIRE 16 -1 (2150 2325)(2150 2275);
WIRE 16 -1 (1950 2325)(2150 2325);
WIRE 16 -1 (2150 2425)(2150 2325);
WIRE 16 -1 (1950 2425)(2150 2425);
WIRE 16 -1 (2150 2475)(2150 2425);
WIRE 16 -1 (1950 2475)(2150 2475);
WIRE 16 -1 (2150 2525)(2150 2475);
WIRE 16 -1 (1950 2525)(2150 2525);
WIRE 16 -1 (2150 2575)(2150 2525);
WIRE 16 -1 (1950 2575)(2150 2575);
WIRE 16 -1 (2150 2575)(2150 2600);
WIRE 16 -1 (2150 2600)(2150 2625);
WIRE 16 -1 (2150 2600)(2500 2600);
WIRE 16 -1 (2500 2675)(2500 2600);
WIRE 16 -1 (2150 2625)(2150 2675);
WIRE 16 -1 (1950 2625)(2150 2625);
WIRE 16 -1 (1950 2675)(2150 2675);
WIRE 16 -1 (1950 2775)(2150 2775);
WIRE 16 -1 (2150 2825)(2150 2775);
WIRE 16 -1 (1950 2825)(2150 2825);
WIRE 16 -1 (2150 2875)(2150 2825);
WIRE 16 -1 (1950 2875)(2150 2875);
WIRE 16 -1 (2150 2925)(2150 2875);
WIRE 16 -1 (1950 2925)(2150 2925);
WIRE 16 -1 (2150 2975)(2150 2925);
WIRE 16 -1 (1950 2975)(2150 2975);
WIRE 16 -1 (2150 3025)(2150 2975);
WIRE 16 -1 (1950 3025)(2150 3025);
WIRE 16 -1 (2150 3075)(2150 3025);
WIRE 16 -1 (1950 3075)(2150 3075);
WIRE 16 -1 (2150 3125)(2150 3075);
WIRE 16 -1 (1950 3125)(2150 3125);
WIRE 16 -1 (2150 3175)(2150 3125);
WIRE 16 -1 (1950 3175)(2150 3175);
WIRE 16 -1 (2150 3225)(2150 3175);
WIRE 16 -1 (1950 3225)(2150 3225);
WIRE 16 -1 (2150 3275)(2150 3225);
WIRE 16 -1 (1950 3275)(2150 3275);
WIRE 16 -1 (2150 3275)(2150 3300);
WIRE 16 -1 (2150 3300)(2150 3325);
WIRE 16 -1 (2500 3300)(2150 3300);
WIRE 16 -1 (2500 3400)(2500 3300);
WIRE 16 -1 (2150 3375)(2150 3325);
WIRE 16 -1 (1950 3325)(2150 3325);
WIRE 16 -1 (1950 3375)(2150 3375);
WIRE 16 -1 (1950 1625)(2325 1625);
WIRE 16 -1 (2325 1625)(2325 1675);
WIRE 16 -1 (1950 1675)(2325 1675);
WIRE 16 -1 (2325 1675)(2325 1725);
WIRE 16 -1 (1950 1725)(2325 1725);
WIRE 16 -1 (2325 1725)(2325 1775);
WIRE 16 -1 (1950 1775)(2325 1775);
WIRE 16 -1 (2325 1775)(2325 1975);
WIRE 16 -1 (2175 1425)(2175 1375);
WIRE 16 -1 (2175 1425)(2175 1450);
WIRE 16 -1 (2175 1425)(1950 1425);
WIRE 16 -1 (2175 1375)(1950 1375);
WIRE 16 -1 (2175 1450)(2175 1475);
WIRE 16 -1 (2175 1450)(3400 1450);
WIRE 16 -1 (3400 1225)(3400 1450);
WIRE 16 -1 (3550 1450)(3400 1450);
WIRE 16 -1 (2175 1475)(2175 1525);
WIRE 16 -1 (2175 1475)(1950 1475);
WIRE 16 -1 (2175 1525)(1950 1525);
WIRE 16 -1 (3550 1550)(3550 1450);
WIRE 16 -1 (2650 1300)(2650 1275);
WIRE 16 -1 (2650 1275)(1950 1275);
DOT 1 (-250 3825);
DOT 1 (3400 1450);
DOT 1 (2175 1450);
DOT 1 (2175 1425);
DOT 1 (2175 1475);
DOT 1 (2150 1925);
DOT 1 (-250 1225);
DOT 1 (2150 2075);
DOT 1 (2325 1725);
DOT 1 (2325 1775);
DOT 1 (-250 4325);
DOT 1 (-250 3775);
DOT 1 (2175 1075);
DOT 1 (2150 2600);
DOT 1 (-3075 3750);
DOT 1 (2150 3925);
DOT 1 (-800 3100);
DOT 1 (-800 3050);
DOT 1 (-800 3000);
DOT 1 (2175 775);
DOT 1 (-800 1450);
DOT 1 (-800 1550);
DOT 1 (-800 1650);
DOT 1 (-800 1750);
DOT 1 (2150 2325);
DOT 1 (-250 2475);
DOT 1 (-250 4525);
DOT 1 (2150 4675);
DOT 1 (-3075 2100);
DOT 1 (-800 1600);
DOT 1 (-800 1850);
DOT 1 (-800 1800);
DOT 1 (-800 1700);
DOT 1 (-800 1950);
DOT 1 (-800 1900);
DOT 1 (-800 2000);
DOT 1 (-800 2100);
DOT 1 (-800 2150);
DOT 1 (-800 2200);
DOT 1 (-800 2250);
DOT 1 (-800 2300);
DOT 1 (-800 2350);
DOT 1 (-800 2400);
DOT 1 (-800 2450);
DOT 1 (-800 2500);
DOT 1 (-800 2800);
DOT 1 (-800 2850);
DOT 1 (-800 2900);
DOT 1 (-800 2950);
DOT 1 (-800 3150);
DOT 1 (-800 3200);
DOT 1 (-800 3250);
DOT 1 (-800 3300);
DOT 1 (-800 3350);
DOT 1 (-800 3400);
DOT 1 (-800 3450);
DOT 1 (-800 3500);
DOT 1 (-800 3550);
DOT 1 (-800 3600);
DOT 1 (-800 3650);
DOT 1 (-800 3750);
DOT 1 (-800 3800);
DOT 1 (-800 3850);
DOT 1 (-800 3900);
DOT 1 (-800 3950);
DOT 1 (-3075 1600);
DOT 1 (-3075 1650);
DOT 1 (-3075 1700);
DOT 1 (-3075 1750);
DOT 1 (-3075 1800);
DOT 1 (-3075 1850);
DOT 1 (-3075 1900);
DOT 1 (-3075 1950);
DOT 1 (-3075 2000);
DOT 1 (-3075 2050);
DOT 1 (-3075 2150);
DOT 1 (-3075 2200);
DOT 1 (-3075 2250);
DOT 1 (-3075 2300);
DOT 1 (-3075 2350);
DOT 1 (-3075 2400);
DOT 1 (-3075 2450);
DOT 1 (-3075 2500);
DOT 1 (-3075 2550);
DOT 1 (-3075 2600);
DOT 1 (-3075 2650);
DOT 1 (-3075 2700);
DOT 1 (-3075 2750);
DOT 1 (-3075 2800);
DOT 1 (-3075 2850);
DOT 1 (-3075 2900);
DOT 1 (-3075 2950);
DOT 1 (-3075 3000);
DOT 1 (-3075 3050);
DOT 1 (-3075 3100);
DOT 1 (-3075 3150);
DOT 1 (-3075 3200);
DOT 1 (-3075 3300);
DOT 1 (-3075 3350);
DOT 1 (-3075 3400);
DOT 1 (-3075 3450);
DOT 1 (-3075 3500);
DOT 1 (-3075 3550);
DOT 1 (-3075 3600);
DOT 1 (-3075 3650);
DOT 1 (-3075 3700);
DOT 1 (-3075 3800);
DOT 1 (-3075 3900);
DOT 1 (-3075 3950);
DOT 1 (-250 1375);
DOT 1 (-250 1425);
DOT 1 (-250 1325);
DOT 1 (-250 1475);
DOT 1 (-250 1525);
DOT 1 (-250 1675);
DOT 1 (-250 1725);
DOT 1 (-250 1925);
DOT 1 (-250 1875);
DOT 1 (-250 1825);
DOT 1 (-250 1775);
DOT 1 (-250 2075);
DOT 1 (-250 2125);
DOT 1 (-250 2175);
DOT 1 (-250 2375);
DOT 1 (-250 2275);
DOT 1 (-250 2425);
DOT 1 (-250 2225);
DOT 1 (-250 2675);
DOT 1 (-250 2875);
DOT 1 (-250 2925);
DOT 1 (-250 2775);
DOT 1 (-250 2725);
DOT 1 (-250 2975);
DOT 1 (-250 3125);
DOT 1 (-250 3075);
DOT 1 (-250 3025);
DOT 1 (-250 3175);
DOT 1 (-250 3225);
DOT 1 (-250 3375);
DOT 1 (-250 3325);
DOT 1 (-250 3275);
DOT 1 (-250 3425);
DOT 1 (-250 3475);
DOT 1 (-250 3675);
DOT 1 (-250 3725);
DOT 1 (-250 3525);
DOT 1 (-250 3575);
DOT 1 (-250 3925);
DOT 1 (-250 3975);
DOT 1 (-250 3875);
DOT 1 (-250 4075);
DOT 1 (-250 4125);
DOT 1 (-250 4175);
DOT 1 (-250 4225);
DOT 1 (-250 4025);
DOT 1 (2150 3025);
DOT 1 (2150 3075);
DOT 1 (2150 3175);
DOT 1 (2150 3125);
DOT 1 (2150 3575);
DOT 1 (2150 3625);
DOT 1 (2150 3675);
DOT 1 (2150 3725);
DOT 1 (2150 3825);
DOT 1 (2150 3775);
DOT 1 (2150 3875);
DOT 1 (2150 3975);
DOT 1 (2150 4075);
DOT 1 (2150 4025);
DOT 1 (2150 4125);
DOT 1 (2150 4175);
DOT 1 (2150 4225);
DOT 1 (-250 4475);
DOT 1 (-250 4425);
DOT 1 (-250 4375);
DOT 1 (-250 4275);
DOT 1 (-250 4575);
DOT 1 (-250 4625);
DOT 1 (2150 4325);
DOT 1 (2150 4275);
DOT 1 (2150 4375);
DOT 1 (2150 4425);
DOT 1 (2150 4475);
DOT 1 (-250 4675);
DOT 1 (-250 4725);
DOT 1 (-250 1625);
DOT 1 (-250 1275);
DOT 1 (2150 4525);
DOT 1 (2150 4575);
DOT 1 (2150 4625);
DOT 1 (2150 4725);
DOT 1 (2150 3225);
DOT 1 (-250 2825);
DOT 1 (-800 3700);
DOT 1 (-250 2025);
DOT 1 (-250 1075);
DOT 1 (2175 925);
DOT 1 (2175 825);
DOT 1 (-3075 1550);
DOT 1 (-3075 1450);
DOT 1 (-3075 1400);
DOT 1 (-250 1175);
DOT 1 (2150 1975);
DOT 1 (-250 1975);
DOT 1 (-800 2050);
DOT 1 (-250 1575);
DOT 1 (-250 2625);
DOT 1 (-250 2575);
DOT 1 (-250 2525);
DOT 1 (2175 1100);
DOT 1 (2150 3525);
DOT 1 (2150 3275);
DOT 1 (2150 3300);
DOT 1 (2150 2975);
DOT 1 (2150 3325);
DOT 1 (2150 2175);
DOT 1 (2150 2225);
DOT 1 (2150 2275);
DOT 1 (2150 2425);
DOT 1 (2150 2475);
DOT 1 (2150 2525);
DOT 1 (2150 2575);
DOT 1 (2150 2625);
DOT 1 (2150 2825);
DOT 1 (2150 2875);
DOT 1 (2150 2925);
DOT 1 (2175 725);
DOT 1 (-250 2325);
DOT 1 (-3075 3250);
DOT 1 (-800 2550);
DOT 1 (-800 2600);
DOT 1 (-800 2650);
DOT 1 (-800 2700);
DOT 1 (-800 2750);
DOT 1 (2150 2025);
DOT 1 (2150 2125);
DOT 1 (-250 1125);
DOT 1 (-250 3625);
DOT 1 (-3075 3850);
DOT 1 (2325 1675);
DOT 1 (2175 1125);
DOT 1 (2175 1025);
DOT 1 (2175 975);
FORCENOTE
ROOM=CPU0
(-3725 450) 0;
DISPLAY LEFT (-3725 450);
DISPLAY 1.723404 (-3725 450);
PAINT PURPLE (-3725 450);
FORCENOTE
BOM_COST=PROC_SOCKET
(-3775 300) 0;
DISPLAY LEFT (-3775 300);
DISPLAY 1.723404 (-3775 300);
PAINT PURPLE (-3775 300);
QUIT
